%FSTAX23Y23*%
%MOIN*%
%SFA1B1*%

%IPPOS*%
%AMD38*
4,1,8,-0.010500,0.010000,-0.010500,-0.010000,0.000000,-0.020400,0.000000,-0.020400,0.010500,-0.010000,0.010500,0.010000,0.000000,0.020400,0.000000,0.020400,-0.010500,0.010000,0.0*
1,1,0.020960,0.000000,0.010000*
1,1,0.020960,0.000000,-0.010000*
1,1,0.020960,0.000000,-0.010000*
1,1,0.020960,0.000000,0.010000*
%
G04~CAMADD=38~8~0.0~0.0~408.8~209.5~104.8~0.0~15~0.0~0.0~0.0~0.0~0~0.0~0.0~0.0~0.0~0~0.0~0.0~0.0~90.0~210.0~409.0*
%ADD38D38*%
%ADD39R,0.020950X0.040880*%
%ADD71R,0.165350X0.125980*%
%ADD84R,0.314960X0.135830*%
%ADD85R,1.354330X0.230320*%
%ADD86R,0.036000X0.173000*%
%ADD87R,0.036000X0.134000*%
%ADD88R,0.036350X0.047370*%
%ADD89R,0.035560X0.043430*%
%ADD90R,0.094610X0.049340*%
%ADD91R,0.049340X0.047370*%
%ADD92R,0.045400X0.039500*%
%ADD93R,0.065090X0.053280*%
%ADD94R,0.220600X0.122170*%
%ADD95R,0.049340X0.051310*%
%ADD96R,0.037530X0.041470*%
%ADD97R,0.051310X0.049340*%
%ADD98R,0.043430X0.047370*%
%ADD99R,0.045400X0.041470*%
%ADD100R,0.017840X0.069020*%
%ADD101R,0.074930X0.061150*%
%ADD102R,0.061150X0.074930*%
%ADD103R,0.069020X0.017840*%
%ADD104O,0.086740X0.031620*%
%ADD105R,0.072960X0.059180*%
%ADD106R,0.025720X0.062330*%
%ADD107R,0.063910X0.069020*%
%ADD108R,0.078870X0.082800*%
%ADD109R,0.047370X0.082800*%
%ADD110R,0.027690X0.098550*%
%ADD111R,0.086740X0.106420*%
%ADD112R,0.027690X0.043430*%
%ADD113O,0.065090X0.025720*%
%ADD114R,0.085560X0.030440*%
%ADD115R,0.033590X0.049340*%
%ADD116R,0.059180X0.082800*%
%ADD117R,0.047370X0.098550*%
%ADD118R,0.047370X0.078870*%
%ADD119R,0.061150X0.035560*%
%ADD120R,0.035560X0.053280*%
%ADD121R,0.049340X0.053280*%
%ADD122R,0.058000X0.208000*%
%ADD123R,0.065090X0.045400*%
%ADD124R,0.039500X0.074930*%
%ADD125R,0.078870X0.017840*%
%ADD126R,0.017840X0.030640*%
%ADD127R,0.034580X0.017840*%
%ADD128R,0.046580X0.042250*%
%ADD129R,0.104460X0.132020*%
%ADD130R,0.041470X0.047370*%
%ADD131R,0.045400X0.047370*%
%ADD132R,0.017840X0.018830*%
%ADD133R,0.018830X0.017840*%
%ADD134R,0.053280X0.065090*%
%ADD135R,0.047370X0.041470*%
%ADD136R,0.047370X0.036350*%
%ADD137R,0.031620X0.033590*%
%ADD138R,0.090870X0.052090*%
%ADD139R,0.047370X0.045400*%
%ADD140R,0.043430X0.035560*%
%ADD141C,0.008000*%
%ADD142C,0.120000*%
%ADD143C,0.128000*%
%ADD144C,0.029660*%
%ADD145R,0.008000X0.008000*%
%ADD146C,0.039500*%
%ADD147C,0.073980*%
%ADD148C,0.069020*%
%ADD149R,0.069020X0.069020*%
%ADD150C,0.083000*%
%ADD151C,0.106420*%
%ADD152O,0.204850X0.106420*%
%ADD153O,0.185170X0.096580*%
%ADD154O,0.096580X0.185170*%
%ADD155C,0.063000*%
%ADD156R,0.063000X0.063000*%
%ADD157C,0.058000*%
%ADD158C,0.258000*%
%ADD159C,0.024000*%
%ADD160C,0.040000*%
%ADD161C,0.208000*%
%LNtimingcard_pcb-1*%
%LPD*%
G36*
X06792Y01181D02*
X06792Y01181D01*
X06793Y01181*
X06793Y0118*
Y0118*
X06797*
X06797Y0118*
X06798Y0118*
X06798Y0118*
X06799Y0118*
X06799Y0118*
X068*
X068Y0118*
X06801Y0118*
X06801Y0118*
X06802Y01179*
Y01179*
X06802*
X06802Y01179*
X06803Y01179*
X06803Y01179*
X06804Y01179*
X06804Y01179*
X06804Y01179*
X06805Y01178*
X06805Y01178*
X06805*
X06805Y01178*
X06806Y01178*
X06806Y01178*
X06807Y01178*
X06807Y01177*
X06807Y01177*
X06808Y01177*
X06808*
X06808Y01177*
X06809Y01177*
X06809Y01177*
X0681Y01176*
X0681Y01176*
X0681Y01176*
X0681Y01176*
X06811Y01176*
X06811Y01175*
X06811Y01175*
X06812Y01175*
X06812Y01175*
X06813Y01174*
X06813Y01174*
X06813Y01174*
X06813Y01174*
X06814Y01174*
X06814Y01173*
X06814Y01173*
X06815Y01173*
X06815Y01173*
X06815Y01173*
X06816Y01172*
X06816Y01172*
X06816Y01172*
X06817Y01171*
X06817Y01171*
X06817Y01171*
X06817Y01171*
X06817Y01171*
X06818Y01171*
X06818Y0117*
X06818Y0117*
X06818Y0117*
X06819Y0117*
X06819Y01169*
X06819Y01169*
X06819Y01169*
X0682Y01168*
X0682Y01168*
X0682Y01168*
X0682Y01168*
X06821Y01167*
X06821Y01167*
X06821Y01167*
X06822Y01167*
X06822Y01166*
X06822Y01166*
X06822Y01165*
X06823Y01165*
X06823Y01165*
X06823Y01165*
X06823Y01164*
X06824Y01164*
X06824Y01163*
X06824Y01163*
X06824Y01163*
X06824Y01163*
X06825Y01162*
X06825Y01162*
X06825Y01161*
X06825Y01161*
X06825Y01161*
X06825Y01161*
X06826Y0116*
X06826Y0116*
X06826Y0116*
X06826Y01159*
X06827Y01159*
X06827Y01158*
X06827Y01158*
X06827Y01157*
X06827Y01157*
Y01157*
X06827Y01157*
X06828Y01156*
X06828Y01156*
X06828Y01156*
X06828Y01155*
X06828Y01155*
X06828Y01154*
Y01154*
X06828Y01154*
X06829Y01154*
X06829Y01153*
X06829Y01153*
X06829Y01152*
Y01152*
X06829Y01152*
X06829Y01151*
X06829Y0115*
X06829Y0115*
Y0115*
X06829*
X0683Y01149*
X0683Y01149*
X0683Y01148*
X0683Y01148*
Y01147*
Y01147*
Y01146*
Y01146*
Y01145*
Y01145*
Y01144*
X0683Y01144*
X0683Y01144*
X0683Y01143*
X06831Y01143*
X06831Y01142*
Y01142*
Y01141*
Y01141*
Y0114*
X06831Y0114*
X0683Y01139*
X0683Y01139*
X0683Y01138*
X0683Y01138*
Y01138*
Y01138*
Y01137*
Y01136*
Y01136*
Y01135*
X0683Y01135*
X0683Y01134*
X0683Y01134*
X06829Y01133*
X06829*
Y01133*
Y01133*
X06829Y01132*
X06829Y01132*
X06829Y01131*
X06829Y01131*
X06829Y01131*
Y01131*
Y01131*
X06829Y0113*
X06829Y0113*
X06828Y01129*
X06828Y01129*
Y01129*
X06828Y01128*
X06828Y01128*
X06828Y01127*
X06828Y01127*
Y01127*
Y01127*
X06828Y01127*
X06828Y01126*
X06827Y01126*
X06827Y01125*
X06827Y01125*
X06827Y01125*
X06827Y01124*
X06827Y01124*
X06826Y01124*
X06826Y01124*
X06826Y01123*
X06826Y01123*
X06826Y01123*
X06826Y01122*
X06825Y01122*
X06825Y01122*
X06825Y01121*
X06825Y01121*
X06825Y01121*
X06825Y0112*
X06824Y0112*
X06824Y0112*
X06824Y01119*
X06824Y01119*
X06824Y01119*
X06823Y01118*
X06823Y01118*
X06823Y01118*
X06822Y01117*
X06822Y01117*
X06822Y01117*
X06822Y01117*
X06822Y01116*
X06821Y01116*
X06821Y01116*
X06821Y01115*
X0682Y01115*
X0682Y01115*
X0682Y01115*
X0682Y01114*
X0682Y01114*
X06819Y01114*
X06819Y01114*
X06819Y01113*
X06819Y01113*
X06819Y01113*
X06818Y01113*
X06818Y01113*
X06818Y01112*
X06818Y01112*
X06818Y01112*
X06817Y01112*
X06817Y01111*
X06817Y01111*
X06816Y01111*
X06816Y01111*
X06815Y01111*
X06815Y0111*
X06815Y0111*
X06815Y0111*
X06815Y0111*
X06814Y01109*
X06814Y01109*
X06813Y01109*
X06813Y01108*
X06813Y01108*
X06813Y01108*
X06812Y01108*
X06812Y01108*
X06811Y01107*
X06811Y01107*
X06811Y01107*
X0681Y01107*
X0681Y01107*
X0681Y01106*
X06809Y01106*
X06809Y01106*
X06809Y01106*
X06808Y01106*
X06808Y01106*
X06807Y01105*
X06807Y01105*
X06807Y01105*
X06806Y01105*
X06806Y01105*
X06805Y01104*
X06805Y01104*
X06805*
X06805Y01104*
X06804Y01104*
X06804Y01104*
X06803Y01104*
X06803*
X06803Y01104*
X06803Y01104*
X06802Y01103*
X06802Y01103*
X06801Y01103*
X06801*
Y01103*
X06801Y01103*
X068Y01103*
X068Y01103*
X06799Y01103*
X06798*
Y01103*
X06798Y01102*
X06797Y01102*
X06797Y01102*
X06796Y01102*
X06744*
X06743Y01102*
X06743Y01102*
X06742Y01102*
X06742Y01103*
X06742Y01103*
X06741*
X06741Y01103*
X0674Y01103*
X0674Y01103*
X06739Y01103*
X06739Y01103*
X06739*
X06738Y01103*
X06738Y01104*
X06738Y01104*
X06737Y01104*
X06737*
X06737Y01104*
X06736Y01104*
X06736Y01104*
X06736Y01104*
X06736*
X06735Y01104*
X06735Y01105*
X06734Y01105*
X06734Y01105*
X06734Y01105*
X06733Y01105*
X06733Y01105*
X06733*
X06733Y01106*
X06732Y01106*
X06732Y01106*
X06731Y01106*
X06731Y01107*
X06731Y01107*
X0673Y01107*
X0673Y01107*
X0673Y01107*
X06729Y01107*
X06729Y01108*
X06728Y01108*
X06728Y01108*
X06728Y01108*
X06728Y01108*
X06727Y01109*
X06727Y01109*
X06726Y01109*
X06726Y01109*
X06726Y0111*
X06726Y0111*
X06725Y0111*
X06725Y0111*
X06725Y01111*
X06725Y01111*
X06724Y01111*
X06724Y01111*
X06724Y01111*
X06723Y01112*
X06723Y01112*
X06723Y01112*
X06723Y01112*
X06723Y01113*
X06722Y01113*
X06722Y01113*
X06722Y01113*
X06722Y01113*
X06722Y01114*
X06721Y01114*
X06721Y01114*
X06721Y01114*
X0672Y01115*
X0672Y01115*
X0672Y01115*
X0672Y01115*
X0672Y01115*
X0672Y01116*
X06719Y01116*
X06719Y01116*
X06719Y01116*
X06719Y01117*
X06718Y01117*
X06718Y01118*
X06718Y01118*
X06718Y01118*
X06718Y01118*
X06718Y01118*
X06717Y01118*
X06717Y01119*
X06717Y01119*
X06716Y0112*
X06716Y0112*
X06716Y0112*
X06716Y01121*
X06716Y01121*
X06716Y01121*
X06715Y01122*
X06715Y01122*
X06715Y01122*
X06715Y01123*
X06715Y01123*
X06714Y01123*
X06714Y01124*
X06714Y01124*
X06714Y01124*
X06714Y01125*
X06714Y01125*
X06713Y01125*
X06713Y01126*
X06713Y01126*
X06713Y01127*
X06713Y01127*
X06713Y01127*
X06713Y01127*
X06712Y01128*
X06712Y01128*
Y01128*
X06712Y01129*
X06712Y01129*
X06712Y01129*
X06712Y0113*
Y0113*
X06712Y0113*
X06711Y01131*
X06711Y01131*
X06711Y01132*
X06711Y01132*
Y01133*
Y01133*
X06711Y01133*
X06711Y01134*
X06711Y01134*
X06711Y01135*
Y01135*
Y01136*
X06711Y01136*
X0671Y01136*
X0671Y01136*
X0671Y01137*
X0671Y01138*
Y01138*
Y01139*
Y01139*
Y0114*
Y0114*
Y01141*
Y01141*
Y01142*
Y01142*
Y01143*
Y01143*
Y01144*
Y01145*
X0671Y01145*
X0671Y01146*
X0671Y01146*
X06711Y01147*
X06711Y01147*
Y01147*
Y01147*
Y01148*
Y01148*
X06711Y01149*
X06711Y01149*
X06711Y0115*
X06711Y0115*
Y01151*
X06711Y01151*
X06711Y01152*
X06711Y01152*
X06712Y01153*
Y01153*
Y01153*
X06712Y01153*
X06712Y01154*
X06712Y01154*
X06712Y01155*
X06712Y01155*
X06713Y01155*
X06713Y01156*
X06713Y01156*
X06713Y01156*
X06713Y01156*
X06713Y01157*
X06713Y01157*
X06714Y01158*
X06714Y01158*
X06714Y01158*
X06714Y01158*
X06714Y01159*
X06714Y01159*
X06714Y0116*
X06715Y0116*
X06715Y0116*
X06715Y01161*
X06715Y01161*
X06715Y01161*
X06715Y01161*
X06716Y01162*
X06716Y01162*
X06716Y01163*
X06716Y01163*
X06716Y01163*
X06717Y01163*
X06717Y01164*
X06717Y01164*
X06717Y01164*
X06717Y01164*
X06718Y01165*
X06718Y01165*
X06718Y01166*
X06719Y01166*
X06719Y01166*
X06719Y01167*
X06719Y01167*
X0672Y01167*
X0672Y01167*
X0672Y01168*
X0672Y01168*
X06721Y01168*
X06721Y01168*
X06721Y01169*
X06722Y01169*
X06722Y01169*
X06722Y0117*
X06722Y0117*
X06723Y0117*
X06723Y0117*
X06723Y01171*
X06723Y01171*
X06723Y01171*
X06724Y01171*
X06724Y01171*
X06724Y01171*
X06724Y01172*
X06725Y01172*
X06725Y01172*
X06725Y01173*
X06725Y01173*
X06726Y01173*
X06726Y01173*
X06727Y01174*
X06727Y01174*
X06727Y01174*
X06727Y01174*
X06728Y01175*
X06728Y01175*
X06728Y01175*
X06729Y01175*
X06729Y01175*
X06729Y01176*
X0673Y01176*
X0673Y01176*
X0673Y01176*
X06731Y01176*
X06731Y01176*
X06732Y01177*
X06732Y01177*
X06732Y01177*
X06733Y01177*
X06733Y01177*
X06734Y01178*
X06734Y01178*
X06734*
X06734Y01178*
X06735Y01178*
X06735Y01178*
X06735Y01178*
X06736Y01179*
X06736Y01179*
X06737Y01179*
X06737*
X06737Y01179*
X06737Y01179*
X06738Y01179*
X06738Y01179*
X06739Y01179*
X06739*
Y01179*
X0674Y0118*
X0674Y0118*
X06741Y0118*
X06741Y0118*
X06741*
X06741Y0118*
X06742Y0118*
X06742Y0118*
X06743Y0118*
X06743Y0118*
X06747*
Y0118*
X06748Y01181*
X06748Y01181*
X06749Y01181*
X06749Y01181*
X0679*
X06791Y01181*
X06791Y01181*
X06791*
X06792Y01181*
G37*
G36*
X05973Y00955D02*
X05973Y00955D01*
X05974Y00955*
X05974Y00954*
X05975*
X05975Y00954*
X05976Y00954*
X05976Y00954*
X05977Y00954*
X05977Y00954*
X05977Y00954*
X05977Y00954*
X05978Y00954*
X05978Y00953*
X05978Y00953*
X05979Y00953*
X05979Y00953*
X0598Y00953*
X0598Y00953*
X0598Y00952*
X05981Y00952*
X05981Y00952*
X05981Y00952*
X05981Y00951*
X05982Y00951*
X05982Y00951*
X05983Y00951*
X05983Y0095*
X05983Y0095*
X05984Y0095*
X05984Y0095*
X05984Y0095*
X05985Y00949*
X05985Y00949*
X05985Y00949*
X05985Y00948*
X05986Y00948*
X05986Y00948*
X05986Y00948*
X05987Y00947*
X05987Y00947*
X05987Y00947*
X05987Y00946*
X05988Y00946*
X05988Y00946*
X05988Y00945*
X05988Y00945*
X05989Y00945*
X05989Y00944*
X05989Y00944*
X05989Y00944*
X05989Y00944*
X0599Y00943*
X0599Y00943*
X0599Y00942*
X0599Y00942*
X0599Y00942*
X05991Y00941*
X05991Y00941*
X05991Y0094*
Y0094*
X05991Y0094*
X05991Y0094*
X05991Y00939*
X05991Y00939*
Y00938*
X05992Y00938*
X05992Y00938*
X05992Y00937*
X05992Y00937*
X05992Y00936*
Y00936*
X05992Y00936*
X05992Y00936*
X05992Y00935*
X05993Y00935*
X05993Y00934*
Y00934*
Y00933*
Y00933*
Y00932*
Y00932*
Y00931*
Y0093*
Y0093*
Y00929*
Y00929*
Y00928*
Y00928*
Y00927*
X05993Y00927*
X05992Y00926*
X05992Y00926*
X05992Y00925*
X05992*
Y00925*
X05992Y00925*
X05992Y00924*
X05992Y00924*
X05992Y00923*
X05991Y00923*
Y00923*
Y00923*
X05991Y00922*
X05991Y00922*
X05991Y00921*
X05991Y00921*
X05991Y00921*
X0599Y0092*
X0599Y0092*
X0599Y0092*
X0599Y00919*
X0599Y00919*
X0599Y00919*
X05989Y00918*
X05989Y00918*
X05989Y00917*
X05989Y00917*
X05989Y00917*
X05988Y00917*
X05988Y00916*
X05988Y00916*
X05987Y00915*
X05987Y00915*
X05987Y00915*
X05987Y00915*
X05986Y00914*
X05986Y00914*
X05986Y00914*
X05985Y00914*
X05985Y00913*
X05985Y00913*
X05985Y00913*
X05984Y00913*
X05984Y00912*
X05984Y00912*
X05984Y00912*
X05984Y00912*
X05983Y00911*
X05983Y00911*
X05982Y00911*
X05982Y00911*
X05982Y0091*
X05982Y0091*
X05981Y0091*
X05981Y0091*
X0598Y00909*
X0598Y00909*
X0598Y00909*
X05979Y00909*
X05979Y00909*
X05979Y00909*
X05978Y00908*
X05978Y00908*
X05977Y00908*
X05977Y00908*
X05977Y00908*
X05977Y00908*
X05976Y00908*
X05976Y00908*
X05976Y00908*
X05975Y00908*
X05975Y00907*
X05974Y00907*
X05974Y00907*
X05973Y00907*
X05972*
X05972Y00907*
X05971Y00907*
X05971Y00907*
X0597Y00906*
X05966*
X05966Y00907*
X05965Y00907*
X05965Y00907*
X05964Y00907*
X05963*
X05963Y00907*
X05962Y00907*
X05962Y00907*
X05961Y00908*
X05961Y00908*
X05961Y00908*
X05961Y00908*
X0596Y00908*
X0596Y00908*
X05959Y00908*
X05959Y00908*
X05958Y00909*
X05958Y00909*
X05958Y00909*
X05958Y00909*
X05957Y00909*
X05957Y00909*
X05956Y00909*
X05956Y0091*
X05956Y0091*
X05956Y0091*
X05955Y0091*
X05955Y00911*
X05954Y00911*
X05954Y00911*
X05954Y00911*
X05954Y00911*
X05953Y00912*
X05953Y00912*
X05953Y00912*
X05952Y00913*
X05952Y00913*
X05952Y00913*
X05951Y00913*
X05951Y00914*
X05951Y00914*
X05951Y00914*
X0595Y00914*
X0595Y00915*
X0595Y00915*
X0595Y00915*
X05949Y00915*
X05949Y00916*
X05949Y00916*
X05949Y00916*
X05948Y00917*
X05948Y00917*
X05948Y00917*
X05948Y00918*
X05948Y00918*
X05948Y00918*
X05948Y00918*
X05947Y00918*
X05947Y00919*
X05947Y00919*
X05947Y0092*
X05946Y0092*
X05946Y0092*
X05946Y00921*
X05946Y00921*
X05946Y00922*
X05946Y00922*
X05946Y00922*
X05945Y00922*
X05945Y00923*
X05945Y00923*
Y00924*
X05945Y00924*
X05945Y00924*
X05945Y00925*
X05945Y00925*
X05945Y00926*
Y00926*
Y00926*
Y00926*
X05944Y00927*
X05944Y00927*
X05944Y00928*
X05944Y00928*
Y00929*
Y00929*
Y0093*
Y0093*
Y00931*
Y00932*
Y00932*
Y00933*
Y00933*
Y00934*
X05944Y00934*
X05944Y00935*
X05944Y00935*
X05945Y00936*
Y00936*
Y00936*
Y00936*
X05945Y00937*
X05945Y00937*
X05945Y00938*
X05945Y00938*
X05945Y00938*
Y00939*
X05945Y00939*
X05945Y0094*
X05946Y0094*
X05946Y0094*
X05946Y00941*
X05946Y00941*
X05946Y00941*
X05947Y00942*
X05947Y00942*
X05947Y00943*
X05947Y00943*
X05947Y00943*
X05947Y00944*
X05948Y00944*
X05948Y00944*
X05948Y00945*
X05948Y00945*
X05949Y00945*
X05949Y00946*
X05949Y00946*
X05949Y00946*
X05949Y00947*
X0595Y00947*
X0595Y00947*
X0595Y00948*
X05951Y00948*
X05951Y00948*
X05951Y00948*
X05951Y00949*
X05952Y00949*
X05952Y00949*
X05953Y0095*
X05953Y0095*
X05953Y0095*
X05953Y0095*
X05954Y0095*
X05954Y00951*
X05954Y00951*
X05955Y00951*
X05955Y00951*
X05955Y00952*
X05955Y00952*
X05956Y00952*
X05956Y00952*
X05957Y00953*
X05957Y00953*
X05957Y00953*
X05958Y00953*
X05958Y00953*
X05959Y00953*
X05959Y00953*
X05959Y00953*
X05959Y00954*
X0596Y00954*
X0596Y00954*
X0596Y00954*
X05961Y00954*
X05961Y00954*
X05962Y00954*
X05962Y00954*
X05962*
X05963Y00955*
X05963Y00955*
X05964Y00955*
X05964Y00955*
X05972*
X05973Y00955*
G37*
G36*
X05972Y00882D02*
X05973Y00882D01*
X05973Y00882*
X05974Y00882*
X05974*
X05974*
X05975Y00881*
X05975Y00881*
X05976Y00881*
X05976Y00881*
X05976Y00881*
X05976*
X05977Y00881*
X05977Y00881*
X05978Y0088*
X05978Y0088*
X05978Y0088*
X05979Y0088*
X05979Y0088*
X05979Y0088*
X0598Y00879*
X0598Y00879*
X0598Y00879*
X05981Y00879*
X05981Y00879*
X05981Y00878*
X05982Y00878*
X05982Y00878*
X05983Y00878*
X05983Y00877*
X05983Y00877*
X05983Y00877*
X05984Y00877*
X05984Y00877*
X05985Y00876*
X05985Y00876*
X05985Y00876*
X05985Y00875*
X05986Y00875*
X05986Y00875*
X05986Y00875*
X05987Y00874*
X05987Y00874*
X05987Y00874*
X05987Y00873*
X05988Y00873*
X05988Y00873*
X05988Y00872*
X05988Y00872*
X05989Y00872*
X05989Y00871*
X05989Y00871*
X05989Y00871*
X05989Y0087*
X0599Y0087*
X0599Y0087*
X0599Y00869*
X0599Y00869*
X0599Y00868*
X0599Y00868*
X05991Y00868*
X05991Y00867*
X05991Y00867*
X05991Y00867*
X05991Y00866*
X05991Y00866*
Y00865*
X05992Y00865*
X05992Y00865*
X05992Y00864*
X05992Y00864*
X05992Y00863*
Y00863*
X05992*
X05992Y00863*
X05992Y00862*
X05993Y00862*
X05993Y00861*
Y00861*
Y0086*
Y0086*
Y00859*
Y00859*
Y00858*
Y00857*
Y00857*
Y00856*
Y00856*
Y00855*
Y00855*
Y00854*
X05993Y00854*
X05992Y00853*
X05992Y00853*
X05992Y00852*
X05992*
Y00852*
X05992Y00852*
X05992Y00851*
X05992Y00851*
X05992Y0085*
X05991Y0085*
Y0085*
X05991Y00849*
X05991Y00849*
X05991Y00848*
X05991Y00848*
X05991Y00848*
X0599Y00847*
X0599Y00847*
X0599Y00847*
X0599Y00847*
X0599Y00846*
X0599Y00846*
X0599Y00846*
X05989Y00845*
X05989Y00845*
X05989Y00845*
X05989Y00844*
X05989Y00844*
X05988Y00843*
X05988Y00843*
X05988Y00843*
X05988Y00843*
X05987Y00842*
X05987Y00842*
X05987Y00842*
X05987Y00841*
X05986Y00841*
X05986Y00841*
X05986Y0084*
X05985Y0084*
X05985Y0084*
X05985Y00839*
X05984Y00839*
X05984Y00839*
X05984Y00839*
X05984Y00839*
X05983Y00838*
X05983Y00838*
X05983Y00838*
X05982Y00838*
X05982Y00837*
X05981Y00837*
X05981Y00837*
X05981Y00837*
X0598Y00836*
X0598Y00836*
X0598Y00836*
X05979Y00836*
X05979Y00836*
X05979Y00836*
X05978Y00835*
X05978Y00835*
X05978Y00835*
X05977Y00835*
X05977Y00835*
X05976Y00835*
X05976*
X05976Y00835*
X05976Y00834*
X05975Y00834*
X05975Y00834*
X05974Y00834*
X05973*
Y00834*
X05973Y00834*
X05972Y00834*
X05972Y00834*
X05971Y00833*
X05965*
X05965Y00834*
X05964Y00834*
X05964Y00834*
X05963Y00834*
Y00834*
X05963*
X05962Y00834*
X05962Y00834*
X05961Y00834*
X05961Y00835*
X05961Y00835*
X05961*
X0596Y00835*
X05959Y00835*
X05959Y00835*
X05959Y00835*
X05958Y00835*
X05958Y00836*
X05958Y00836*
X05957Y00836*
X05957Y00836*
X05957Y00836*
X05956Y00836*
X05956Y00837*
X05955Y00837*
X05955Y00837*
X05955Y00838*
X05955Y00838*
X05954Y00838*
X05954Y00838*
X05953Y00838*
X05953Y00839*
X05953Y00839*
X05953Y00839*
X05952Y0084*
X05952Y0084*
X05952Y0084*
X05951Y0084*
X05951Y00841*
X05951Y00841*
X05951Y00841*
X0595Y00841*
X0595Y00842*
X0595Y00842*
X0595Y00842*
X05949Y00843*
X05949Y00843*
X05949Y00843*
X05948Y00844*
X05948Y00844*
X05948Y00844*
X05948Y00844*
X05948Y00845*
X05947Y00845*
X05947Y00846*
X05947Y00846*
X05947Y00846*
X05947Y00847*
X05946Y00847*
X05946Y00847*
X05946Y00847*
X05946Y00848*
X05946Y00848*
X05946Y00849*
X05946Y00849*
X05946Y00849*
X05945Y00849*
X05945Y0085*
X05945Y0085*
Y00851*
X05945Y00851*
X05945Y00851*
X05945Y00852*
X05945Y00852*
X05945Y00853*
Y00853*
X05944Y00853*
X05944Y00854*
X05944Y00854*
X05944Y00855*
Y00855*
Y00856*
Y00856*
Y00857*
Y00857*
Y00858*
Y00859*
Y00859*
Y0086*
Y0086*
Y00861*
X05944Y00861*
X05944Y00862*
X05944Y00862*
X05945Y00863*
Y00863*
X05945Y00863*
X05945Y00864*
X05945Y00864*
X05945Y00865*
Y00865*
Y00865*
X05945Y00866*
X05945Y00866*
X05945Y00867*
X05946Y00867*
X05946Y00867*
X05946Y00867*
X05946Y00868*
X05946Y00868*
X05946Y00868*
X05947Y00869*
X05947Y00869*
X05947Y0087*
X05947Y0087*
X05947Y0087*
X05948Y00871*
X05948Y00871*
X05948Y00871*
X05948Y00871*
X05948Y00872*
X05949Y00872*
X05949Y00873*
X05949Y00873*
X05949Y00873*
X0595Y00873*
X0595Y00873*
X0595Y00874*
X0595Y00874*
X0595Y00874*
X05951Y00874*
X05951Y00875*
X05951Y00875*
X05951Y00875*
X05952Y00875*
X05952Y00876*
X05952Y00876*
X05953Y00876*
X05953Y00877*
X05953Y00877*
X05953Y00877*
X05954Y00877*
X05954Y00878*
X05955Y00878*
X05955Y00878*
X05955Y00878*
X05955Y00879*
X05956Y00879*
X05956Y00879*
X05957Y00879*
X05957Y00879*
X05957Y0088*
X05958Y0088*
X05958Y0088*
X05958Y0088*
X05959Y0088*
X05959Y0088*
X05959Y00881*
X0596Y00881*
X05961Y00881*
X05961*
X05961Y00881*
X05961Y00881*
X05962Y00881*
X05962Y00881*
X05963Y00882*
X05963*
X05964Y00882*
X05964Y00882*
X05965Y00882*
X05965Y00882*
X05972*
X05972Y00882*
G37*
G36*
X06916Y00899D02*
X06917Y00899D01*
X06917Y00898*
X06918Y00898*
X06918*
X06919*
X0692Y00898*
X0692Y00898*
X06921Y00898*
X06921Y00898*
X06921*
X06922Y00898*
X06922Y00898*
X06923Y00897*
X06923Y00897*
X06923Y00897*
X06923Y00897*
X06924Y00897*
X06924Y00897*
X06925Y00897*
X06925Y00897*
X06925Y00897*
X06925Y00897*
X06926Y00896*
X06926Y00896*
X06927Y00896*
X06927Y00896*
X06927Y00896*
X06928Y00896*
X06928Y00896*
X06928Y00895*
X06929Y00895*
X06929Y00895*
X06929Y00895*
X0693Y00895*
X0693Y00894*
X06931Y00894*
X06931Y00894*
X06931Y00894*
X06931Y00894*
X06932Y00893*
X06932Y00893*
X06932Y00893*
X06933Y00893*
X06933Y00893*
X06934Y00892*
X06934Y00892*
X06934Y00892*
X06935Y00892*
X06935Y00891*
X06935Y00891*
X06936Y00891*
X06936Y00891*
X06936Y0089*
X06936Y0089*
X06937Y0089*
X06937Y0089*
X06937Y0089*
X06938Y00889*
X06938Y00889*
X06938Y00889*
X06939Y00888*
X06939Y00888*
X06939Y00888*
X06939Y00888*
X0694Y00887*
X0694Y00887*
X0694Y00887*
X0694Y00887*
X06941Y00886*
X06941Y00886*
X06941Y00886*
X06942Y00885*
X06942Y00885*
X06942Y00885*
X06942Y00884*
X06943Y00884*
X06943Y00884*
X06943Y00884*
X06943Y00883*
X06943Y00883*
X06944Y00883*
X06944Y00882*
X06944Y00882*
X06944Y00882*
X06945Y00881*
X06945Y00881*
X06945Y00881*
X06945Y0088*
X06946Y0088*
X06946Y0088*
X06946Y00879*
X06946Y00879*
X06946Y00879*
X06947Y00878*
X06947Y00878*
X06947Y00877*
X06947Y00877*
X06947Y00877*
X06948Y00876*
X06948Y00876*
X06948Y00875*
X06948Y00875*
X06948Y00875*
X06948Y00875*
X06948Y00874*
X06948Y00874*
X06948Y00874*
X06949Y00874*
X06949Y00873*
X06949Y00873*
Y00873*
X06949Y00872*
X06949Y00872*
X06949Y00872*
X06949Y00871*
Y00871*
X0695Y00871*
X0695Y0087*
X0695Y0087*
X0695Y00869*
X0695Y00869*
Y00869*
Y00869*
X0695Y00868*
X0695Y00868*
X06951Y00867*
X06951Y00867*
Y00866*
Y00866*
Y00865*
X06951Y00865*
X06951Y00865*
X06951Y00864*
X06951Y00864*
X06951Y00863*
Y00863*
Y00862*
Y00862*
Y00861*
Y00861*
Y0086*
Y0086*
Y00859*
Y00859*
Y00858*
Y00857*
Y00857*
Y00856*
Y00856*
Y00855*
X06951Y00855*
X06951Y00854*
X06951Y00854*
X06951Y00853*
X06951*
Y00853*
Y00853*
Y00852*
X06951Y00852*
X0695Y00851*
X0695Y00851*
X0695Y0085*
Y0085*
Y0085*
X0695Y00849*
X0695Y00849*
X0695Y00848*
X0695Y00848*
X06949Y00848*
Y00848*
X06949Y00847*
X06949Y00847*
X06949Y00846*
X06949Y00846*
Y00846*
X06949Y00846*
X06949Y00845*
X06948Y00845*
X06948Y00844*
X06948Y00844*
X06948Y00844*
X06948Y00843*
X06948Y00843*
X06947Y00843*
X06947Y00842*
X06947Y00842*
X06947Y00841*
X06947Y00841*
X06946Y00841*
X06946Y0084*
X06946Y0084*
X06946Y0084*
X06946Y00839*
X06945Y00839*
X06945Y00838*
X06945Y00838*
X06945Y00838*
X06945Y00838*
X06944Y00837*
X06944Y00837*
X06944Y00837*
X06944Y00836*
X06944Y00836*
X06943Y00836*
X06943Y00835*
X06943Y00835*
X06942Y00835*
X06942Y00834*
X06942Y00834*
X06942Y00834*
X06942Y00834*
X06941Y00834*
X06941Y00834*
X06941Y00833*
X06941Y00833*
X0694Y00833*
X0694Y00832*
X0694Y00832*
X0694Y00832*
X06939Y00832*
X06939Y00831*
X06939Y00831*
X06939Y00831*
X06938Y00831*
X06938Y0083*
X06938Y0083*
X06938Y0083*
X06938Y0083*
X06937Y0083*
X06937Y00829*
X06937Y00829*
X06937Y00829*
X06936Y00829*
X06936Y00828*
X06936Y00828*
X06935Y00828*
X06935Y00828*
X06935Y00828*
X06935Y00827*
X06934Y00827*
X06934Y00827*
X06933Y00826*
X06933Y00826*
X06933Y00826*
X06932Y00826*
X06932Y00826*
X06932Y00826*
X06932Y00825*
X06931Y00825*
X06931Y00825*
X0693Y00825*
X0693Y00824*
X0693Y00824*
X06929Y00824*
X06929Y00824*
X06929Y00824*
X06928Y00824*
X06928Y00823*
X06927Y00823*
X06927Y00823*
X06927Y00823*
X06926Y00823*
X06926Y00823*
X06926Y00823*
X06925Y00822*
X06925Y00822*
X06924Y00822*
X06924Y00822*
X06924Y00822*
X06924Y00822*
X06923Y00822*
X06923Y00822*
X06922Y00822*
X06922*
X06922Y00821*
X06921Y00821*
X06921Y00821*
X0692Y00821*
X06919*
X06919*
X06919Y00821*
X06918Y00821*
X06918Y00821*
X06917Y00821*
X06916*
X06916*
X06916Y0082*
X06915Y0082*
X06915Y0082*
X06914Y0082*
X06914*
X06913Y0082*
X06913Y0082*
X06913*
X06912Y0082*
X06912Y0082*
X06908*
X06908Y0082*
X06907Y0082*
X06907Y0082*
X06906Y00821*
X06904*
X06904Y00821*
X06903Y00821*
X06903Y00821*
X06902Y00821*
X06902*
X06902*
X06901Y00821*
X06901Y00821*
X069Y00821*
X069Y00822*
X069Y00822*
X069Y00822*
X06899Y00822*
X06899Y00822*
X06898Y00822*
X06898Y00822*
X06898Y00822*
X06897Y00822*
X06897Y00822*
X06896Y00823*
X06896Y00823*
X06896Y00823*
X06896Y00823*
X06895Y00823*
X06895Y00823*
X06895Y00823*
X06894Y00824*
X06894Y00824*
X06893Y00824*
X06893Y00824*
X06893Y00824*
X06892Y00824*
X06892Y00825*
X06892Y00825*
X06891Y00825*
X06891Y00825*
X06891Y00825*
X0689Y00826*
X0689Y00826*
X0689Y00826*
X06889Y00826*
X06889Y00826*
X06888Y00827*
X06888Y00827*
X06888Y00827*
X06888Y00827*
X06887Y00828*
X06887Y00828*
X06886Y00828*
X06886Y00828*
X06886Y00829*
X06886Y00829*
X06886Y00829*
X06885Y00829*
X06885Y00829*
X06885Y00829*
X06885Y0083*
X06884Y0083*
X06884Y0083*
X06883Y00831*
X06883Y00831*
X06883Y00831*
X06883Y00831*
X06882Y00832*
X06882Y00832*
X06882Y00832*
X06882Y00832*
X06882Y00832*
X06881Y00833*
X06881Y00833*
X06881Y00833*
X0688Y00834*
X0688Y00834*
X0688Y00835*
X0688Y00835*
X0688Y00835*
X0688Y00835*
X06879Y00835*
X06879Y00835*
X06879Y00835*
X06879Y00836*
X06879Y00836*
X06878Y00837*
X06878Y00837*
X06878Y00837*
X06878Y00837*
X06877Y00838*
X06877Y00838*
X06877Y00839*
X06877Y00839*
X06877Y00839*
X06876Y0084*
X06876Y0084*
X06876Y0084*
X06876Y0084*
X06876Y0084*
X06876Y00841*
X06875Y00841*
X06875Y00841*
X06875Y00842*
X06875Y00842*
X06875Y00842*
X06875Y00843*
X06874Y00843*
X06874Y00844*
X06874Y00844*
X06874Y00845*
X06874Y00845*
X06874Y00845*
X06874Y00845*
X06874Y00845*
X06873Y00846*
X06873Y00846*
X06873Y00847*
X06873Y00847*
X06873Y00847*
X06873Y00847*
X06873Y00848*
X06872Y00848*
X06872Y00849*
X06872Y00849*
Y0085*
Y0085*
X06872Y0085*
X06872Y00851*
X06872Y00851*
X06872Y00852*
Y00852*
Y00852*
X06872Y00853*
X06871Y00853*
X06871Y00854*
X06871Y00854*
Y00855*
Y00855*
Y00856*
Y00856*
Y00857*
Y00857*
Y00858*
Y00859*
Y00859*
Y0086*
Y0086*
Y00861*
Y00861*
Y00862*
Y00862*
Y00863*
Y00863*
Y00864*
Y00865*
X06871Y00865*
X06871Y00866*
X06872Y00866*
X06872Y00867*
Y00867*
Y00867*
Y00867*
X06872Y00868*
X06872Y00868*
X06872Y00869*
X06872Y00869*
Y00869*
Y00869*
X06872Y0087*
X06872Y0087*
X06873Y00871*
X06873Y00871*
X06873Y00871*
X06873Y00872*
X06873Y00872*
X06873Y00873*
X06873Y00873*
X06873Y00873*
X06873Y00873*
X06874Y00874*
X06874Y00874*
X06874Y00875*
X06874Y00875*
X06874Y00875*
X06874Y00876*
X06875Y00876*
X06875Y00876*
X06875Y00877*
X06875Y00877*
X06875Y00877*
X06875Y00877*
X06876Y00878*
X06876Y00878*
X06876Y00878*
X06876Y00879*
X06876Y00879*
X06876Y0088*
X06877Y0088*
X06877Y0088*
X06877Y00881*
X06877Y00881*
X06877Y00881*
X06878Y00882*
X06878Y00882*
X06878Y00882*
X06879Y00883*
X06879Y00883*
X06879Y00883*
X06879Y00883*
X06879Y00884*
X0688Y00884*
X0688Y00885*
X0688Y00885*
X0688Y00885*
X06881Y00885*
X06881Y00886*
X06881Y00886*
X06882Y00886*
X06882Y00887*
X06882Y00887*
X06882Y00887*
X06883Y00887*
X06883Y00888*
X06883Y00888*
X06883Y00888*
X06884Y00888*
X06884Y00889*
X06884Y00889*
X06885Y00889*
X06885Y0089*
X06885Y0089*
X06885Y0089*
X06886Y0089*
X06886Y00891*
X06887Y00891*
X06887Y00891*
X06887Y00891*
X06887Y00891*
X06888Y00892*
X06888Y00892*
X06888Y00892*
X06889Y00892*
X06889Y00893*
X06889Y00893*
X0689Y00893*
X0689Y00893*
X0689Y00893*
X06891Y00894*
X06891Y00894*
X06892Y00894*
X06892Y00894*
X06892Y00894*
X06893Y00895*
X06893Y00895*
X06893Y00895*
X06894Y00895*
X06894Y00895*
X06894Y00896*
X06895Y00896*
X06895Y00896*
X06896Y00896*
X06896Y00896*
X06896Y00896*
X06896Y00896*
X06897Y00897*
X06897Y00897*
X06897Y00897*
X06898Y00897*
X06898Y00897*
X06899Y00897*
X06899Y00897*
X06899Y00897*
X06899Y00897*
X069Y00897*
X069Y00898*
X06901Y00898*
X06901Y00898*
X06901*
X06901*
X06902Y00898*
X06902Y00898*
X06903Y00898*
X06903Y00898*
X06904*
X06904Y00898*
X06905Y00899*
X06906Y00899*
X06906Y00899*
X06916*
X06916Y00899*
G37*
G36*
X06629Y01181D02*
X0663Y01181D01*
X0663Y01181*
X06631Y0118*
X06631Y0118*
X06635*
X06635Y0118*
X06636Y0118*
X06636Y0118*
X06637Y0118*
X06637Y0118*
X06637*
X06637Y0118*
X06638Y0118*
X06638Y0118*
X06639Y01179*
X06639Y01179*
X06639*
X06639Y01179*
X0664Y01179*
X0664Y01179*
X06641Y01179*
X06641Y01179*
X06641*
X06642Y01179*
X06642Y01179*
X06643Y01178*
X06643Y01178*
X06643*
X06643Y01178*
X06644Y01178*
X06644Y01178*
X06645Y01178*
X06645Y01177*
X06645Y01177*
X06646Y01177*
X06646Y01177*
X06646Y01177*
X06647Y01176*
X06647Y01176*
X06647Y01176*
X06648Y01176*
X06648Y01176*
X06649Y01176*
X06649Y01175*
X06649Y01175*
X0665Y01175*
X0665Y01175*
X0665Y01174*
X06651Y01174*
X06651Y01174*
X06651Y01174*
X06652Y01174*
X06652Y01173*
X06652Y01173*
X06653Y01173*
X06653Y01173*
X06653Y01173*
X06653Y01172*
X06654Y01172*
X06654Y01172*
X06654Y01171*
X06655Y01171*
X06655Y01171*
X06655Y01171*
X06656Y0117*
X06656Y0117*
X06656Y0117*
X06656Y0117*
X06657Y01169*
X06657Y01169*
X06657Y01169*
X06657Y01168*
X06658Y01168*
X06658Y01168*
X06658Y01168*
X06659Y01167*
X06659Y01167*
X06659Y01167*
X06659Y01167*
X0666Y01166*
X0666Y01166*
X0666Y01165*
X06661Y01165*
X06661Y01165*
X06661Y01165*
X06661Y01164*
X06661Y01164*
X06662Y01164*
X06662Y01163*
X06662Y01163*
X06662Y01163*
X06662Y01162*
X06663Y01162*
X06663Y01162*
X06663Y01161*
X06663Y01161*
X06664Y01161*
X06664Y0116*
X06664Y0116*
X06664Y0116*
X06664Y01159*
X06664Y01159*
X06664Y01159*
X06665Y01158*
X06665Y01158*
X06665Y01158*
X06665Y01158*
X06665Y01157*
X06665Y01157*
X06666Y01156*
X06666Y01156*
X06666Y01156*
X06666Y01156*
X06666Y01155*
X06666Y01155*
X06666Y01154*
X06666Y01154*
X06666Y01154*
X06666Y01154*
X06667Y01153*
X06667Y01153*
X06667Y01153*
X06667Y01153*
X06667Y01152*
X06667Y01152*
X06667Y01151*
X06667Y01151*
Y0115*
X06668Y0115*
X06668Y01149*
X06668Y01149*
X06668Y01148*
Y01148*
Y01147*
Y01147*
Y01147*
X06668Y01147*
X06668Y01146*
X06668Y01146*
X06668Y01145*
Y01145*
Y01144*
Y01143*
Y01143*
Y01142*
Y01142*
Y01141*
Y01141*
Y0114*
Y0114*
Y01139*
X06668Y01139*
X06668Y01139*
Y01138*
X06668Y01138*
X06668Y01137*
X06668Y01137*
X06668Y01136*
Y01136*
Y01136*
Y01135*
Y01135*
Y01134*
X06668Y01134*
X06668Y01133*
X06668Y01133*
X06667Y01132*
Y01132*
X06667Y01132*
X06667Y01131*
X06667Y01131*
X06667Y0113*
X06667Y0113*
X06667Y0113*
X06667Y01129*
X06666Y01129*
X06666Y01129*
X06666Y01128*
X06666Y01128*
X06666Y01128*
X06666Y01127*
X06666Y01127*
X06666Y01127*
X06666Y01127*
X06666Y01126*
X06665Y01126*
X06665Y01125*
X06665Y01125*
X06665Y01125*
X06665Y01124*
X06664Y01124*
X06664Y01124*
X06664Y01123*
X06664Y01123*
X06664Y01122*
X06664Y01122*
X06663Y01122*
X06663Y01121*
X06663Y01121*
X06663Y01121*
X06662Y0112*
X06662Y0112*
X06662Y0112*
X06662Y01119*
X06662Y01119*
X06661Y01119*
X06661Y01118*
X06661Y01118*
X0666Y01118*
X0666Y01117*
X0666Y01117*
X0666Y01117*
X0666Y01117*
X06659Y01116*
X06659Y01116*
X06659Y01116*
X06659Y01115*
X06658Y01115*
X06658Y01115*
X06658Y01115*
X06658Y01114*
X06658Y01114*
X06657Y01114*
X06657Y01114*
X06657Y01114*
X06657Y01113*
X06656Y01113*
X06656Y01113*
X06656Y01113*
X06656Y01112*
X06656Y01112*
X06655Y01112*
X06655Y01112*
X06655Y01112*
X06655Y01111*
X06654Y01111*
X06654Y01111*
X06653Y01111*
X06653Y01111*
Y01111*
X06653Y0111*
X06653Y0111*
X06653Y0111*
X06652Y01109*
X06652Y01109*
X06651Y01109*
X06651Y01109*
X06651Y01109*
X06651Y01109*
X06651Y01108*
X0665Y01108*
X0665Y01108*
X06649Y01108*
X06649Y01108*
X06649Y01107*
X06649Y01107*
X06648Y01107*
X06648Y01107*
X06647Y01106*
X06647Y01106*
X06647Y01106*
X06647Y01106*
X06647Y01106*
X06646Y01106*
X06646Y01106*
X06646Y01106*
X06645Y01105*
X06645Y01105*
X06644Y01105*
X06644Y01105*
X06644*
X06644Y01105*
X06643Y01105*
X06643Y01105*
X06643Y01104*
X06643Y01104*
X06642Y01104*
X06642Y01104*
X06641Y01104*
X06641Y01104*
X0664*
X0664Y01104*
X0664Y01104*
X06639Y01103*
X06639Y01103*
X06639*
X06639Y01103*
X06638Y01103*
X06638Y01103*
X06637Y01103*
X06637Y01103*
X06636*
Y01103*
X06635Y01102*
X06635Y01102*
X06634Y01102*
X06634Y01102*
X06554*
X06554Y01102*
X06553Y01102*
X06553Y01102*
X06552Y01102*
X06552Y01102*
X0655*
X0655Y01102*
X06549Y01101*
X06549Y01101*
X06548Y01101*
X06548Y01101*
X06547*
Y01101*
X06547Y01101*
X06546Y01101*
X06546Y01101*
X06545Y01101*
X06545*
X06545*
X06545Y011*
X06545Y011*
X06544Y011*
X06544Y011*
X06544Y011*
X06543Y011*
X06543Y011*
X06543Y01099*
X06543Y01099*
X06542Y01099*
X06542Y01099*
X06541Y01099*
X06541Y01099*
X06541Y01099*
X0654Y01098*
X0654Y01098*
X0654Y01098*
X06539Y01098*
X06539Y01098*
X06539Y01098*
X06539Y01097*
X06538Y01097*
X06538Y01097*
X06537Y01097*
X06537Y01096*
X06537Y01096*
X06536Y01096*
X06536Y01096*
X06536Y01096*
X06536Y01096*
X06536Y01096*
X06535Y01095*
X06535Y01095*
X06535Y01095*
X06535Y01095*
X06534Y01094*
X06534Y01094*
X06533Y01094*
X06533Y01094*
X06533Y01094*
X06533Y01093*
X06533Y01093*
X06532Y01093*
X06532Y01093*
X06532Y01092*
X06532Y01092*
X06531Y01092*
X06531Y01092*
X06531Y01091*
X06531Y01091*
X06531Y01091*
X06531Y01091*
X0653Y0109*
X0653Y0109*
X0653Y0109*
X06529Y01089*
X06529Y01089*
X06529Y01089*
X06529Y01089*
X06529Y01088*
X06529Y01088*
X06528Y01088*
X06528Y01088*
X06528Y01087*
X06528Y01087*
X06528Y01086*
X06527Y01086*
X06527Y01086*
X06527Y01086*
X06527Y01086*
X06527Y01085*
X06527Y01085*
X06526Y01085*
X06526Y01084*
X06526Y01084*
X06526Y01084*
X06526Y01084*
X06526Y01083*
X06526Y01083*
X06526Y01083*
X06526Y01082*
X06525Y01082*
X06525Y01081*
X06525Y01081*
X06525Y01081*
X06525Y0108*
X06525Y0108*
Y0108*
X06524Y0108*
X06524Y01079*
X06524Y01079*
X06524*
Y01079*
X06524Y01078*
X06524Y01078*
X06524Y01077*
X06523Y01077*
Y01077*
Y01076*
Y01076*
Y01075*
X06523Y01075*
X06523Y01074*
X06523Y01074*
X06523Y01073*
Y01073*
Y01073*
Y01073*
Y01072*
Y01072*
Y01071*
Y0107*
Y0107*
Y01069*
Y01069*
Y01069*
Y01069*
X06523Y01068*
X06523Y01068*
X06523Y01067*
X06523Y01067*
Y01066*
Y01066*
Y01065*
X06524Y01065*
X06524Y01065*
X06524Y01064*
X06524Y01063*
Y01063*
X06524*
X06524Y01063*
X06524Y01062*
X06525Y01062*
Y01062*
X06525Y01062*
X06525Y01061*
X06525Y01061*
X06525Y0106*
X06525Y0106*
X06525Y0106*
X06525Y0106*
X06525Y01059*
X06526Y01059*
X06526Y01059*
X06526Y01058*
X06526Y01058*
X06526Y01058*
X06526Y01057*
X06527Y01057*
X06527Y01057*
X06527Y01057*
X06527Y01056*
X06527Y01056*
X06527Y01056*
X06527Y01056*
X06528Y01055*
X06528Y01055*
X06528Y01055*
X06528Y01055*
X06528Y01054*
X06529Y01054*
X06529Y01053*
X06529Y01053*
X06529Y01053*
X06529Y01052*
X0653Y01052*
X0653Y01052*
X0653Y01052*
X0653Y01051*
X0653Y01051*
X06531Y01051*
X06531Y01051*
X06531Y0105*
X06532Y0105*
X06532Y0105*
X06532Y0105*
X06532Y01049*
X06532Y01049*
X06533Y01049*
X06533Y01049*
X06533Y01048*
X06533Y01048*
X06534Y01048*
X06534Y01048*
X06534Y01047*
X06534Y01047*
X06534Y01047*
X06535Y01047*
X06535Y01047*
X06535Y01047*
X06536Y01046*
X06536Y01046*
X06536Y01046*
X06537Y01046*
X06537Y01046*
X06537Y01045*
X06538Y01045*
X06538Y01045*
X06538Y01045*
X06538Y01044*
X06539Y01044*
X06539Y01044*
X06539Y01044*
X0654Y01044*
X0654Y01043*
X0654Y01043*
X06541Y01043*
X06541Y01043*
X06542Y01043*
X06542Y01043*
X06542Y01042*
X06543Y01042*
X06543Y01042*
X06543Y01042*
X06543Y01042*
X06544Y01042*
X06544Y01042*
X06545Y01042*
X06545Y01042*
X06545Y01041*
X06545Y01041*
X06546Y01041*
X06546Y01041*
Y01041*
X06547*
X06547Y01041*
X06548Y01041*
X06548Y01041*
X06549Y0104*
Y0104*
X06549*
X0655Y0104*
X0655Y0104*
X06551Y0104*
X06551Y0104*
X06551Y0104*
X06977*
X06977Y0104*
X06977Y0104*
X06978*
X06978Y0104*
X06979Y0104*
X06979Y0104*
X0698Y01039*
X0698Y01039*
X06982*
X06982Y01039*
X06983Y01039*
X06983Y01039*
X06984Y01039*
X06984*
X06984Y01039*
X06985Y01039*
X06985Y01039*
X06986Y01038*
X06986Y01038*
X06986*
X06987Y01038*
X06987Y01038*
X06988Y01038*
X06988Y01038*
X06988*
X06988Y01038*
X06989Y01037*
X06989Y01037*
X06989Y01037*
X06989*
X0699Y01037*
X0699Y01037*
X06991Y01037*
X06991Y01036*
X06991Y01036*
X06992Y01036*
X06992Y01036*
X06992Y01036*
X06993Y01036*
X06993Y01035*
X06993Y01035*
X06994Y01035*
X06994Y01035*
X06994Y01035*
X06995Y01035*
X06995Y01035*
X06996Y01034*
X06996Y01034*
X06996Y01034*
X06996Y01034*
X06997Y01033*
X06997Y01033*
X06998Y01033*
X06998Y01033*
X06998Y01033*
X06998Y01032*
X06999Y01032*
X06999Y01032*
X06999Y01031*
X07Y01031*
X07Y01031*
X07Y01031*
X07Y01031*
X07Y0103*
X07001Y0103*
X07001Y0103*
X07001Y0103*
X07002Y0103*
X07002Y01029*
X07002Y01029*
X07003Y01029*
X07003Y01029*
X07003Y01028*
X07003Y01028*
X07003Y01028*
X07004Y01028*
X07004Y01027*
X07004Y01027*
X07004Y01027*
X07004Y01027*
X07004Y01027*
X07005Y01027*
X07005Y01026*
X07005Y01026*
X07005Y01026*
X07005Y01025*
X07006Y01025*
X07006Y01025*
X07006Y01025*
X07006Y01025*
X07006Y01024*
X07007Y01024*
X07007Y01024*
X07007Y01023*
X07008Y01023*
X07008Y01023*
X07008Y01023*
X07008Y01022*
X07008Y01022*
X07009Y01021*
X07009Y01021*
X07009Y01021*
X07009Y0102*
X0701Y0102*
X0701Y0102*
X0701Y01019*
X0701Y01019*
X0701Y01019*
X0701Y01019*
X0701Y01018*
X0701Y01018*
X07011Y01018*
X07011Y01017*
X07011Y01017*
X07011Y01017*
X07011Y01017*
X07011Y01016*
X07012Y01016*
X07012Y01015*
Y01015*
X07012Y01015*
X07012Y01015*
X07012Y01014*
X07012Y01014*
X07012Y01014*
X07012Y01014*
X07013Y01013*
X07013Y01013*
X07013Y01013*
X07013Y01012*
X07013Y01012*
X07013Y01012*
X07013Y01011*
X07013Y0101*
Y0101*
X07013*
X07014Y0101*
X07014Y01009*
X07014Y01009*
X07014Y01008*
Y01008*
Y01008*
X07014Y01008*
X07014Y01007*
X07014Y01007*
X07014Y01006*
X07014Y01006*
Y01005*
Y01005*
Y01004*
Y01003*
Y01003*
Y01002*
Y01002*
Y01001*
Y01001*
Y01*
Y01*
Y00999*
Y00999*
Y00998*
Y00998*
Y00997*
Y00996*
Y00996*
Y00995*
X07014Y00995*
X07014Y00994*
X07014Y00994*
X07014Y00993*
X07014*
Y00993*
Y00993*
X07014Y00992*
X07014Y00992*
X07014Y00991*
X07013Y00991*
X07013*
Y0099*
X07013Y0099*
X07013Y00989*
X07013Y00989*
X07013Y00988*
X07013Y00988*
X07013Y00988*
X07013Y00988*
X07012Y00987*
X07012Y00987*
X07012Y00987*
Y00987*
X07012Y00986*
X07012Y00986*
X07012Y00985*
X07011Y00985*
X07011Y00985*
X07011Y00985*
X07011Y00984*
X07011Y00984*
X07011Y00984*
X07011Y00983*
X0701Y00983*
X0701Y00983*
X0701Y00982*
X0701Y00982*
X0701Y00982*
X0701Y00981*
X0701Y00981*
X07009Y00981*
X07009Y0098*
X07009Y0098*
X07009Y00979*
X07008Y00979*
X07008Y00979*
X07008Y00979*
X07008Y00979*
X07008Y00978*
X07008Y00978*
X07007Y00977*
X07007Y00977*
X07007Y00977*
X07006Y00977*
X07006Y00976*
X07006Y00976*
Y00976*
X07006Y00976*
X07006Y00976*
X07005Y00975*
X07005Y00975*
X07005Y00974*
X07005Y00974*
X07005Y00974*
X07004Y00974*
X07004Y00974*
X07004Y00973*
X07003Y00973*
X07003Y00973*
X07003Y00973*
X07003Y00972*
X07003Y00972*
X07002Y00972*
X07002Y00972*
X07002Y00971*
X07002Y00971*
X07001Y00971*
X07001Y00971*
X07001Y0097*
X07Y0097*
X07Y0097*
X06999Y00969*
X06999Y00969*
X06999Y00969*
X06999Y00969*
X06999Y00969*
X06999Y00969*
X06998Y00968*
X06998Y00968*
X06997Y00968*
X06997Y00968*
X06997Y00968*
X06997Y00967*
X06996Y00967*
X06996Y00967*
X06995Y00967*
X06995Y00967*
X06995Y00966*
X06995Y00966*
X06994Y00966*
X06994Y00966*
X06994Y00966*
X06993Y00965*
X06993Y00965*
X06992Y00965*
X06992Y00965*
X06992*
X06992Y00965*
X06991Y00965*
X06991Y00965*
X06991Y00964*
X0699Y00964*
X0699Y00964*
X0699Y00964*
X0699Y00964*
X06989Y00964*
X06989Y00963*
X06988Y00963*
X06988*
X06988Y00963*
X06988Y00963*
X06987Y00963*
X06987Y00963*
X06986Y00963*
X06986Y00963*
X06986Y00962*
X06985Y00962*
X06985Y00962*
X06984Y00962*
X06984*
X06984Y00962*
X06983Y00962*
X06983Y00962*
X06982Y00962*
X06981*
X06981*
X06981Y00961*
X0698Y00961*
X0698Y00961*
X06979Y00961*
X067*
X067*
X067Y00961*
X06699Y00961*
X06699Y00961*
X06698Y00961*
X06697*
X06697Y0096*
X06696Y0096*
X06696Y0096*
X06695Y0096*
X06695*
X06695Y0096*
X06694Y0096*
X06694Y00959*
X06693Y00959*
X06693*
X06693*
X06692Y00959*
X06692Y00959*
X06692Y00959*
X06691Y00959*
X06691Y00959*
X0669Y00958*
X0669Y00958*
X0669Y00958*
X0669Y00958*
X06689Y00958*
X06689Y00958*
X06689Y00958*
X06688Y00957*
X06688Y00957*
X06688Y00957*
X06688Y00957*
X06687Y00957*
X06687Y00957*
X06686Y00957*
X06686Y00956*
X06686Y00956*
X06686Y00956*
X06685Y00956*
X06685Y00955*
X06685Y00955*
X06685Y00955*
X06685Y00955*
X06684Y00955*
X06684Y00955*
X06684Y00954*
X06683Y00954*
X06683Y00954*
X06682Y00954*
X06682Y00954*
X06682Y00953*
X06682Y00953*
X06682Y00953*
X06681Y00953*
X06681Y00952*
X06681Y00952*
X0668Y00952*
X0668Y00951*
X0668Y00951*
X0668Y00951*
X0668Y00951*
X06679Y00951*
X06679Y0095*
X06679Y0095*
X06679Y0095*
X06678Y0095*
X06678Y00949*
X06678Y00949*
X06678Y00949*
X06678Y00949*
X06678Y00948*
X06677Y00948*
X06677Y00948*
X06677Y00948*
X06677Y00947*
X06676Y00947*
X06676Y00946*
X06676Y00946*
X06676Y00946*
X06676Y00946*
X06675Y00945*
X06675Y00945*
X06675Y00945*
X06675Y00944*
X06675Y00944*
X06675Y00944*
X06674Y00943*
X06674Y00943*
X06674Y00942*
X06674Y00942*
X06674Y00942*
X06673Y00941*
X06673Y00941*
X06673Y00941*
X06673Y00941*
X06673Y0094*
X06673Y0094*
X06673Y00939*
X06673Y00939*
Y00939*
X06673Y00939*
X06672Y00938*
X06672Y00938*
X06672Y00938*
Y00938*
X06672Y00937*
X06672Y00936*
X06672Y00936*
X06672Y00936*
Y00935*
Y00935*
Y00935*
Y00934*
X06672Y00934*
X06671Y00933*
X06671Y00933*
X06671Y00932*
Y00932*
Y00932*
Y00931*
Y0093*
Y0093*
Y00929*
Y00929*
Y00928*
Y00928*
Y00928*
Y00928*
X06671Y00927*
X06671Y00927*
X06672Y00926*
X06672Y00926*
Y00925*
Y00925*
Y00924*
X06672Y00924*
X06672Y00923*
X06672Y00923*
X06672Y00922*
Y00922*
X06672Y00922*
X06672Y00922*
X06673Y00921*
X06673Y00921*
Y00921*
X06673Y00921*
X06673Y0092*
X06673Y0092*
X06673Y00919*
X06673Y00919*
X06673Y00919*
X06673Y00918*
X06674Y00918*
X06674Y00918*
X06674Y00917*
X06674Y00917*
X06674Y00917*
X06675Y00916*
X06675Y00916*
X06675Y00916*
X06675Y00915*
X06675Y00915*
X06675Y00915*
X06676Y00914*
X06676Y00914*
X06676Y00914*
X06676Y00914*
X06676Y00913*
X06676Y00913*
X06677Y00913*
X06677Y00912*
X06677Y00912*
X06677Y00912*
X06677Y00912*
X06678Y00911*
X06678Y00911*
X06678Y0091*
X06678Y0091*
X06679Y0091*
X06679Y0091*
X06679Y0091*
X06679Y0091*
X06679Y00909*
X0668Y00909*
X0668Y00909*
X0668Y00909*
X0668Y00908*
X0668Y00908*
X06681Y00908*
X06681Y00908*
X06681Y00907*
X06681Y00907*
X06682Y00907*
X06682Y00907*
X06682Y00907*
X06682Y00907*
X06682Y00907*
X06683Y00906*
X06683Y00906*
X06683Y00906*
X06684Y00905*
X06684Y00905*
X06684Y00905*
X06684Y00905*
X06685Y00905*
X06685Y00904*
X06686Y00904*
X06686Y00904*
X06686Y00904*
X06686Y00904*
X06687Y00903*
X06687Y00903*
X06687Y00903*
X06688Y00903*
X06688Y00902*
X06688Y00902*
X06689Y00902*
X06689Y00902*
X06689Y00902*
X06689Y00902*
X0669Y00902*
X0669Y00902*
X06691Y00902*
X06691Y00901*
X06691Y00901*
X06692Y00901*
X06692Y00901*
X06692Y00901*
X06692Y00901*
X06693Y00901*
X06693Y009*
X06693Y009*
X06694*
X06694Y009*
X06695Y009*
X06695Y009*
Y009*
X06695*
X06696Y009*
X06696Y009*
X06697Y009*
X06697Y00899*
Y00899*
X06699*
X06699Y00899*
X067Y00899*
X06701Y00899*
X06701Y00899*
X06701*
X06803*
X06803Y00899*
X06804Y00899*
X06804Y00898*
X06805Y00898*
X06805*
X06805*
X06806Y00898*
X06807Y00898*
X06807Y00898*
X06807Y00898*
X06807*
X06808*
X06808Y00898*
X06809Y00898*
X06809Y00897*
X0681Y00897*
X0681Y00897*
X0681Y00897*
X0681Y00897*
X06811Y00897*
X06811Y00897*
X06811Y00897*
X06811Y00897*
X06812Y00897*
X06812Y00896*
X06813Y00896*
X06813Y00896*
X06813Y00896*
X06814Y00896*
X06814Y00896*
X06815Y00896*
X06815Y00895*
X06815Y00895*
X06816Y00895*
X06816Y00895*
X06816Y00895*
X06817Y00894*
X06817Y00894*
X06817Y00894*
X06818Y00894*
X06818Y00894*
X06818Y00894*
X06819Y00893*
X06819Y00893*
X0682Y00893*
X0682Y00893*
X0682Y00893*
X0682Y00893*
X0682Y00892*
X06821Y00892*
X06821Y00892*
X06821Y00891*
X06822Y00891*
X06822Y00891*
X06822Y00891*
X06822Y00891*
X06822Y00891*
X06823Y00891*
X06823Y0089*
X06823Y0089*
X06824Y0089*
X06824Y0089*
X06824Y00889*
X06825Y00889*
X06825Y00889*
X06825Y00889*
X06825Y00889*
X06825Y00888*
X06825Y00888*
X06826Y00888*
X06826Y00888*
X06826Y00887*
X06826Y00887*
X06826Y00887*
X06827Y00887*
X06827Y00887*
X06827Y00886*
X06827Y00886*
X06828Y00886*
X06828Y00886*
X06828Y00885*
X06828Y00885*
X06828Y00885*
X06829Y00885*
X06829Y00885*
X06829Y00884*
X06829Y00884*
X06829Y00884*
X0683Y00884*
X0683Y00883*
X0683Y00883*
X0683Y00883*
X0683Y00882*
X06831Y00882*
X06831Y00882*
X06831Y00882*
X06832Y00881*
X06832Y00881*
X06832Y0088*
X06832Y0088*
X06832Y0088*
X06832Y00879*
X06833Y00879*
X06833Y00879*
X06833Y00879*
X06833Y00878*
X06834Y00878*
X06834Y00878*
X06834Y00878*
X06834Y00878*
X06834Y00877*
X06834Y00877*
X06834Y00877*
X06834Y00877*
X06834Y00876*
X06835Y00876*
X06835Y00875*
X06835Y00875*
X06835Y00875*
X06835Y00875*
X06835Y00874*
X06835Y00874*
X06835Y00874*
X06835Y00874*
X06835Y00874*
X06836Y00873*
X06836Y00873*
X06836Y00872*
Y00872*
X06836Y00872*
X06836Y00871*
X06836Y00871*
X06836Y0087*
X06837Y0087*
Y0087*
X06837Y00869*
X06837Y00869*
X06837Y00868*
X06837Y00868*
Y00867*
Y00867*
Y00867*
X06837Y00867*
X06837Y00866*
X06838Y00866*
X06838Y00865*
Y00865*
Y00864*
Y00863*
Y00863*
Y00862*
Y00862*
Y00861*
Y00861*
Y0086*
Y0086*
Y00859*
Y00859*
Y00858*
Y00857*
Y00857*
Y00856*
Y00856*
Y00855*
Y00855*
Y00854*
Y00854*
X06838Y00853*
X06837Y00853*
X06837Y00852*
X06837Y00852*
Y00852*
Y00851*
X06837Y0085*
X06837Y0085*
X06837Y00849*
X06837Y00849*
X06836Y00849*
Y00849*
X06836Y00848*
X06836Y00848*
X06836Y00847*
X06836Y00847*
Y00847*
X06836Y00847*
X06836Y00846*
X06835Y00846*
X06835Y00846*
Y00846*
X06835Y00845*
X06835Y00845*
X06835Y00844*
X06835Y00844*
X06835Y00844*
X06834Y00843*
X06834Y00843*
X06834Y00843*
X06834Y00842*
X06834Y00842*
X06834Y00842*
X06834Y00841*
X06833Y00841*
X06833Y00841*
X06833Y00841*
X06833Y0084*
X06833Y0084*
X06833Y0084*
X06832Y00839*
X06832Y00839*
X06832Y00838*
X06832Y00838*
X06831Y00838*
X06831Y00838*
X06831Y00838*
X06831Y00837*
X06831Y00837*
X0683Y00836*
X0683Y00836*
X0683Y00836*
X0683Y00835*
X06829Y00835*
X06829Y00835*
X06829Y00835*
X06829Y00834*
X06829Y00834*
X06828Y00834*
X06828Y00833*
X06828Y00833*
X06827Y00833*
X06827Y00832*
X06827Y00832*
X06827Y00832*
X06827Y00832*
X06826Y00832*
X06826Y00832*
X06826Y00831*
X06826Y00831*
X06826Y00831*
X06825Y00831*
X06825Y0083*
X06825Y0083*
X06825Y0083*
X06824Y00829*
X06824Y00829*
X06823Y00829*
X06823Y00829*
X06823Y00829*
X06823Y00828*
X06822Y00828*
X06822Y00828*
X06822Y00828*
X06821Y00827*
X06821Y00827*
X06821Y00827*
X0682Y00827*
X0682Y00826*
X06819Y00826*
X06819Y00826*
X06819Y00826*
X06819Y00826*
X06818Y00825*
X06818Y00825*
X06818Y00825*
X06817Y00825*
X06817Y00825*
X06817Y00825*
X06816Y00824*
X06816Y00824*
X06816Y00824*
X06815Y00824*
X06815Y00824*
X06815Y00824*
X06814Y00823*
X06814Y00823*
X06813Y00823*
X06813Y00823*
X06812Y00823*
X06812Y00823*
X06812Y00823*
X06812Y00822*
X06811Y00822*
X06811Y00822*
X06811Y00822*
X06811Y00822*
X0681Y00822*
X0681Y00822*
X06809Y00822*
X06809Y00822*
X06809Y00822*
X06809Y00821*
X06808Y00821*
X06808Y00821*
X06807Y00821*
X06806*
X06806*
X06806Y00821*
X06805Y00821*
X06805Y00821*
X06804Y00821*
X06803*
X06802Y0082*
X06802Y0082*
X06801Y0082*
X06801Y0082*
X068*
X06799Y0082*
X06799Y0082*
X06637*
X06637Y0082*
X06636Y0082*
X06633*
X06632Y0082*
X06632Y0082*
X06631Y00819*
X06631Y00819*
X0663*
X0663*
X0663Y00819*
X06629Y00819*
X06629Y00819*
X06628Y00819*
X06628*
X06628*
X06628Y00819*
X06627Y00818*
X06627Y00818*
X06626Y00818*
X06626Y00818*
X06626Y00818*
X06626Y00818*
X06626Y00818*
X06625Y00818*
X06625Y00818*
X06624Y00817*
X06624Y00817*
X06624*
X06624Y00817*
X06623Y00817*
X06623Y00817*
X06623Y00817*
X06622Y00816*
X06622Y00816*
X06622Y00816*
X06621Y00816*
X06621Y00816*
X0662Y00815*
X0662Y00815*
X0662Y00815*
X06619Y00815*
X06619Y00815*
X06619Y00815*
X06619Y00814*
X06618Y00814*
X06618Y00814*
X06618Y00814*
X06617Y00814*
X06617Y00813*
X06617Y00813*
X06617Y00813*
X06616Y00812*
X06616Y00812*
X06616Y00812*
X06615Y00812*
X06615Y00812*
X06615Y00811*
X06615Y00811*
X06614Y00811*
X06614Y00811*
X06614Y00811*
X06614Y0081*
X06614Y0081*
X06613Y0081*
X06613Y0081*
X06613Y00809*
X06613Y00809*
X06612Y00808*
X06612Y00808*
X06612Y00808*
X06612Y00808*
X06611Y00807*
X06611Y00807*
X06611Y00807*
X06611Y00807*
X06611Y00806*
X0661Y00806*
X0661Y00806*
X0661Y00806*
X0661Y00805*
X0661Y00805*
X06609Y00804*
X06609Y00804*
X06609Y00804*
X06609Y00804*
X06609Y00803*
X06609Y00803*
X06609Y00803*
X06608Y00803*
X06608Y00802*
X06608Y00802*
X06608Y00802*
X06608Y00801*
X06608Y00801*
X06608Y00801*
X06607Y008*
X06607Y008*
X06607Y008*
X06607Y008*
X06607Y00799*
X06607Y00799*
X06607Y00799*
X06607Y00799*
X06607Y00798*
X06606Y00798*
X06606Y00797*
X06606Y00797*
X06606Y00797*
X06606Y00796*
X06606Y00796*
X06606Y00795*
Y00795*
Y00795*
Y00795*
X06606Y00794*
X06606Y00794*
X06605Y00793*
X06605Y00793*
Y00793*
Y00792*
Y00792*
Y00791*
Y0079*
Y0079*
Y00789*
Y00789*
Y00788*
Y00788*
Y00787*
Y00787*
Y00786*
Y00786*
Y00785*
X06605Y00785*
X06606Y00784*
X06606Y00784*
X06606Y00783*
Y00783*
Y00783*
Y00783*
X06606Y00782*
X06606Y00782*
X06606Y00781*
X06606Y00781*
X06606Y00781*
X06606Y00781*
X06607Y0078*
X06607Y0078*
X06607Y0078*
X06607Y00779*
X06607Y00779*
X06607Y00779*
X06607Y00778*
X06607Y00778*
X06607Y00778*
X06608Y00777*
X06608Y00777*
X06608Y00777*
X06608Y00776*
X06608Y00776*
X06608Y00776*
X06609Y00775*
X06609Y00775*
X06609Y00775*
X06609Y00775*
X06609Y00774*
X06609Y00774*
X06609Y00774*
X0661Y00773*
X0661Y00773*
X0661Y00773*
X0661Y00772*
X06611Y00772*
X06611Y00771*
X06611Y00771*
X06611Y00771*
X06611Y00771*
X06611Y00771*
X06612Y00771*
X06612Y0077*
X06612Y0077*
X06612Y00769*
X06612Y00769*
X06613Y00769*
X06613Y00769*
X06613Y00768*
X06613Y00768*
X06613Y00768*
X06614Y00768*
X06614Y00768*
X06614Y00768*
X06614Y00767*
X06614Y00767*
X06615Y00767*
X06615Y00767*
X06615Y00766*
X06615Y00766*
X06616Y00766*
X06616Y00766*
X06616Y00766*
X06616Y00766*
X06617Y00765*
X06617Y00765*
X06617Y00765*
X06618Y00764*
X06618Y00764*
X06618Y00764*
X06618Y00764*
X06619Y00764*
X06619Y00763*
X0662Y00763*
X0662Y00763*
X0662*
X0662Y00763*
X0662Y00763*
X06621Y00762*
X06621Y00762*
X06622Y00762*
X06622Y00762*
X06622Y00762*
X06623Y00761*
X06623Y00761*
X06623Y00761*
X06624Y00761*
X06624Y00761*
X06624Y00761*
X06625Y0076*
X06625Y0076*
X06625*
X06625Y0076*
X06626Y0076*
X06626Y0076*
X06627Y0076*
X06627Y0076*
X06627Y00759*
X06628*
X06628Y00759*
X06629Y00759*
X06629Y00759*
X0663Y00759*
X0663*
X0663*
X06631Y00759*
X06631Y00759*
X06632Y00758*
X06632Y00758*
X06632*
X06635*
X06636Y00758*
X06636Y00758*
X06637Y00758*
X06637Y00758*
X06747*
X06748Y00758*
X06748Y00758*
X06749Y00757*
X06749Y00757*
X0675*
X0675Y00757*
X06751Y00757*
X06751Y00757*
X06752Y00757*
X06752Y00757*
X06752Y00757*
X06752Y00756*
X06753Y00756*
X06753Y00756*
X06753Y00756*
X06754Y00756*
X06754Y00756*
X06755Y00756*
X06755Y00756*
X06755Y00756*
X06755Y00756*
X06756Y00755*
X06756Y00755*
X06757Y00755*
X06757Y00755*
X06757Y00755*
X06757Y00755*
X06758Y00755*
X06758Y00754*
X06759Y00754*
X06759Y00754*
X06759Y00754*
X0676Y00754*
X0676Y00754*
X0676Y00753*
X06761Y00753*
X06761Y00753*
X06761Y00753*
X06761Y00753*
X06762Y00753*
X06762Y00752*
X06762Y00752*
X06763Y00752*
X06763Y00752*
X06764Y00751*
X06764Y00751*
X06764Y00751*
X06764Y00751*
X06765Y00751*
X06765Y0075*
X06766Y0075*
X06766Y0075*
X06766Y0075*
X06766Y00749*
X06767Y00749*
X06767Y00749*
X06767Y00749*
X06767Y00749*
X06767Y00749*
X06768Y00748*
X06768Y00748*
X06769Y00748*
X06769Y00747*
X06769Y00747*
X06769Y00747*
X0677Y00747*
X0677Y00746*
X0677Y00746*
X0677Y00746*
X06771Y00745*
X06771Y00745*
X06771Y00745*
X06772Y00744*
X06772Y00744*
X06772Y00744*
X06772Y00744*
X06772Y00743*
X06773Y00743*
X06773Y00743*
X06773Y00742*
X06774Y00742*
X06774Y00742*
X06774Y00741*
X06774Y00741*
X06774Y00741*
X06775Y0074*
X06775Y0074*
X06775Y0074*
X06775Y00739*
X06775Y00739*
X06775Y00739*
X06776Y00739*
X06776Y00738*
X06776Y00738*
X06776Y00738*
X06777Y00737*
X06777Y00737*
X06777Y00737*
X06777Y00736*
X06777Y00736*
X06777Y00736*
X06777Y00735*
X06778Y00735*
X06778Y00735*
X06778Y00735*
X06778Y00734*
X06778Y00734*
X06778Y00734*
X06779Y00733*
X06779Y00733*
X06779Y00732*
X06779Y00732*
X06779Y00732*
X06779Y00731*
X06779Y00731*
X06779Y00731*
X06779Y00731*
X06779Y0073*
X0678Y0073*
X0678Y00729*
X0678Y00729*
X0678Y00729*
X0678Y00729*
X0678Y00728*
X0678Y00728*
X0678Y00727*
Y00727*
Y00726*
Y00726*
Y00726*
X06781Y00725*
X06781Y00725*
X06781Y00724*
X06781Y00724*
Y00723*
Y00723*
Y00722*
Y00722*
Y00721*
Y00721*
Y00721*
X06781Y00721*
X06781Y0072*
X06781Y0072*
X06781Y00719*
Y00719*
Y00718*
X06781Y00717*
X06781Y00717*
X06781Y00716*
X06781Y00716*
Y00716*
Y00715*
Y00715*
Y00714*
Y00714*
Y00713*
Y00713*
X06781Y00712*
X06781Y00712*
X06781Y00711*
X0678Y00711*
Y00711*
Y0071*
Y0071*
X0678Y00709*
X0678Y00709*
X0678Y00708*
X0678Y00708*
X0678Y00708*
X0678Y00708*
X0678Y00707*
X06779Y00707*
X06779Y00706*
X06779Y00706*
X06779Y00706*
X06779Y00706*
X06779Y00705*
X06779Y00705*
X06779Y00705*
X06779Y00705*
X06779Y00704*
X06778Y00704*
X06778Y00703*
X06778Y00703*
X06778Y00703*
X06778Y00702*
X06778Y00702*
X06778Y00701*
X06777Y00701*
X06777Y00701*
X06777Y007*
X06777Y007*
X06777Y007*
X06777Y00699*
X06776Y00699*
X06776Y00699*
X06776Y00698*
X06776Y00698*
X06775Y00697*
X06775Y00697*
X06775Y00697*
X06775Y00697*
X06775Y00696*
X06774Y00696*
X06774Y00696*
X06774Y00695*
X06774Y00695*
X06774Y00694*
X06773Y00694*
X06773Y00694*
X06773Y00694*
X06772Y00693*
X06772Y00693*
X06772Y00693*
X06772Y00692*
X06772Y00692*
X06771Y00692*
X06771Y00691*
X06771Y00691*
X0677Y00691*
X0677Y00691*
X0677Y0069*
X0677Y0069*
X06769Y0069*
X06769Y0069*
X06769Y00689*
X06769Y00689*
X06769Y00689*
X06768Y00689*
X06768Y00688*
X06768Y00688*
X06767Y00688*
X06767Y00688*
X06767Y00687*
X06767Y00687*
X06766Y00687*
X06766Y00687*
X06766Y00686*
X06765Y00686*
X06765Y00686*
X06765Y00686*
X06765Y00685*
X06764Y00685*
X06764Y00685*
X06764Y00685*
X06764Y00685*
X06763Y00684*
X06763Y00684*
X06762Y00684*
X06762Y00684*
X06762Y00683*
X06762Y00683*
X06761Y00683*
X06761Y00683*
X0676Y00683*
X0676Y00682*
X0676Y00682*
X06759Y00682*
X06759Y00682*
X06759Y00682*
X06758Y00682*
X06758Y00681*
X06758Y00681*
X06757Y00681*
X06757Y00681*
X06756Y00681*
X06756Y00681*
X06756Y00681*
X06756Y0068*
X06755Y0068*
X06755Y0068*
X06754Y0068*
X06754Y0068*
X06753*
X06753*
X06753Y0068*
X06752Y0068*
X06752Y00679*
X06751Y00679*
X06364*
X06364Y00679*
X06364Y00679*
X06363Y00679*
X06363Y00679*
X06363Y00679*
X06363Y00678*
Y00678*
Y00677*
Y00677*
Y00676*
Y00676*
Y00675*
Y00675*
Y00674*
Y00674*
Y00673*
Y00673*
Y00672*
Y00672*
Y00671*
Y0067*
Y0067*
Y00669*
Y00669*
Y00668*
Y00668*
Y00667*
Y00667*
Y00666*
Y00666*
Y00665*
Y00664*
Y00664*
Y00663*
Y00663*
Y00662*
Y00662*
Y00661*
Y00661*
Y0066*
Y0066*
Y00659*
Y00659*
Y00658*
Y00657*
Y00657*
Y00656*
Y00656*
Y00655*
Y00655*
Y00654*
Y00654*
Y00653*
Y00653*
Y00652*
Y00652*
Y00651*
Y0065*
Y0065*
Y00649*
Y00649*
Y00648*
Y00648*
Y00647*
Y00647*
Y00646*
Y00646*
Y00645*
Y00644*
Y00644*
Y00643*
Y00643*
Y00642*
Y00642*
Y00641*
Y00641*
Y0064*
Y0064*
Y00639*
Y00639*
Y00638*
Y00637*
Y00637*
Y00636*
Y00636*
Y00635*
Y00635*
Y00634*
Y00634*
Y00633*
Y00633*
Y00632*
Y00632*
Y00631*
Y0063*
Y0063*
Y00629*
Y00629*
Y00628*
Y00628*
Y00627*
Y00627*
X06363Y00626*
X06363Y00626*
X06363Y00625*
X06362Y00625*
X06362Y00624*
X06362Y00624*
X06362Y00624*
X06362Y00623*
X06362Y00623*
X06361Y00622*
X06361Y00622*
X06361Y00622*
X0636Y00621*
X0636Y00621*
X0636Y00621*
X06359Y0062*
X06359Y0062*
X06359Y0062*
X06358Y0062*
X06358Y0062*
X06357Y0062*
X06357Y00619*
X06357Y00619*
X06356Y00619*
X06356Y00619*
X06355Y00619*
X06252*
X06251Y00619*
X06251Y00619*
X0625Y00619*
X0625Y00619*
X0625Y00619*
X0625Y00619*
X06249Y0062*
X06249Y0062*
X06248Y0062*
X06248Y0062*
X06247Y00621*
X06247Y00621*
X06247Y00621*
X06247Y00621*
X06246Y00622*
X06246Y00622*
X06246Y00622*
X06245Y00623*
X06245Y00623*
X06245Y00623*
X06245Y00624*
X06245Y00624*
X06244Y00625*
X06244Y00625*
X06244Y00626*
X06244Y00626*
Y00627*
Y00627*
Y00628*
Y00628*
Y00629*
Y00629*
Y0063*
Y0063*
Y00631*
Y00632*
Y00632*
Y00633*
Y00633*
Y00634*
Y00634*
Y00635*
Y00635*
Y00636*
Y00636*
Y00637*
Y00637*
Y00638*
Y00639*
Y00639*
Y0064*
Y0064*
Y00641*
Y00641*
Y00642*
Y00642*
Y00643*
Y00643*
Y00644*
Y00644*
Y00645*
Y00646*
Y00646*
Y00647*
Y00647*
Y00648*
Y00648*
Y00649*
Y00649*
Y0065*
Y0065*
Y00651*
Y00652*
Y00652*
Y00653*
Y00653*
Y00654*
Y00654*
Y00655*
Y00655*
Y00656*
Y00656*
Y00657*
Y00657*
Y00657*
X06244Y00658*
X06244Y00658*
X06244Y00659*
X06244Y00659*
X06244Y00659*
X06243Y00659*
X06243Y00659*
X06243Y00659*
X06243*
X06243Y00659*
X06243Y00659*
X06243Y00659*
X06242Y00659*
X06242Y00658*
X06242Y00658*
X06242Y00657*
X06242Y00657*
Y00657*
Y00656*
Y00656*
Y00655*
Y00655*
Y00654*
Y00654*
Y00653*
Y00653*
Y00652*
Y00652*
Y00651*
Y0065*
Y0065*
Y00649*
Y00649*
Y00648*
Y00648*
Y00647*
Y00647*
Y00646*
Y00646*
Y00645*
Y00644*
Y00644*
Y00643*
Y00643*
Y00642*
Y00642*
Y00641*
Y00641*
Y0064*
Y0064*
Y00639*
Y00639*
Y00638*
Y00637*
Y00637*
Y00636*
Y00636*
Y00635*
Y00635*
Y00634*
Y00634*
Y00633*
Y00633*
Y00632*
Y00632*
Y00631*
Y0063*
Y0063*
Y00629*
Y00629*
Y00628*
Y00628*
Y00627*
Y00627*
Y00626*
Y00626*
X06242Y00625*
X06242Y00625*
X06242Y00624*
X06241Y00624*
X06241Y00623*
X06241Y00623*
X0624Y00622*
X0624Y00622*
X0624Y00622*
X0624Y00622*
X06239Y00621*
X06239Y00621*
X06239Y00621*
X06238Y00621*
X06238Y0062*
X06238Y0062*
X06237Y0062*
X06237Y0062*
X06236Y00619*
X06236Y00619*
X06236Y00619*
X06236Y00619*
X06235Y00619*
X06235Y00619*
X06234Y00619*
X06181*
X06181Y00619*
X0618Y00619*
X0618Y00619*
X06179Y00619*
X06179Y0062*
X06178Y0062*
X06178Y0062*
X06178Y0062*
X06177Y0062*
X06177Y0062*
X06176Y00621*
X06176Y00621*
X06176Y00621*
X06176Y00622*
X06175Y00622*
X06175Y00622*
X06175Y00623*
X06175Y00623*
X06174Y00624*
X06174Y00624*
X06174Y00625*
X06174Y00625*
X06174Y00625*
Y00625*
X06174Y00625*
X06174Y00626*
X06173Y00626*
X06173Y00627*
X06173Y00627*
Y00628*
Y00628*
Y00629*
Y00629*
Y0063*
Y0063*
Y00631*
Y00632*
Y00632*
Y00633*
Y00633*
Y00634*
Y00634*
Y00635*
Y00635*
Y00636*
Y00636*
Y00637*
Y00637*
Y00638*
Y00639*
Y00639*
Y0064*
Y0064*
Y00641*
Y00641*
Y00642*
Y00642*
Y00643*
Y00643*
Y00644*
Y00644*
Y00645*
Y00646*
Y00646*
Y00647*
Y00647*
Y00648*
Y00648*
Y00649*
Y00649*
Y0065*
Y0065*
Y00651*
Y00652*
Y00652*
Y00653*
Y00653*
Y00654*
Y00654*
Y00655*
Y00655*
Y00656*
Y00656*
Y00657*
Y00657*
Y00658*
Y00659*
Y00659*
Y0066*
Y0066*
Y00661*
Y00661*
Y00662*
Y00662*
Y00663*
Y00663*
Y00664*
Y00664*
Y00665*
Y00666*
Y00666*
Y00667*
Y00667*
Y00668*
Y00668*
Y00669*
Y00669*
Y0067*
Y0067*
Y00671*
X06173Y00671*
X06173Y00672*
Y00672*
Y00673*
Y00673*
Y00674*
Y00674*
Y00674*
Y00674*
X06173Y00675*
X06173Y00675*
X06173Y00675*
X06173Y00675*
X06172Y00676*
X06172Y00676*
X06172Y00676*
X06172Y00677*
X06172Y00677*
X06172Y00677*
X06172Y00677*
X06171Y00678*
X06171Y00678*
X06171Y00678*
X06171Y00678*
X0617Y00678*
X0617Y00679*
X0617Y00679*
X06169Y00679*
X06169Y00679*
X06169Y00679*
X06169Y00679*
X06168Y00679*
X06168Y00679*
X06168*
X06167*
X06167*
X06167Y00679*
X06166Y00679*
X06166Y00679*
X06166Y00679*
X06166Y00679*
X06165Y00679*
X06165Y00679*
X06165Y00678*
X06165Y00678*
X06164Y00678*
X06164Y00678*
X06164Y00678*
X06164Y00678*
X06163Y00677*
X06163Y00677*
X06163Y00677*
X06163Y00677*
X06163Y00677*
X06163Y00676*
X06162Y00676*
X06162Y00676*
Y00676*
X06162Y00675*
X06162Y00675*
Y00675*
Y00675*
Y00674*
Y00674*
X06162Y00673*
X06162Y00673*
Y00673*
Y00672*
X06162Y00672*
X06162Y00672*
Y00671*
Y0067*
Y0067*
Y00669*
Y00669*
Y00668*
Y00668*
Y00667*
Y00667*
Y00666*
Y00666*
Y00665*
Y00664*
Y00664*
Y00663*
Y00663*
Y00662*
Y00662*
Y00661*
Y00661*
Y0066*
Y0066*
Y00659*
Y00659*
Y00658*
Y00657*
Y00657*
Y00656*
Y00656*
Y00655*
Y00655*
Y00654*
Y00654*
Y00653*
Y00653*
Y00652*
Y00652*
Y00651*
Y0065*
Y0065*
Y00649*
Y00649*
Y00648*
X06162Y00648*
X06162Y00647*
X06162Y00647*
X06161Y00646*
Y00646*
X06161Y00646*
X06161Y00645*
X06161Y00645*
X06161Y00644*
X0616Y00644*
X0616Y00643*
X0616Y00643*
X0616Y00643*
X06159Y00642*
X06159Y00642*
X06159Y00642*
X06158Y00642*
X06158Y00641*
X06158Y00641*
X06158Y00641*
X06157Y0064*
X06157Y0064*
X06156Y0064*
X06156Y0064*
X06156Y0064*
X06155Y0064*
X06155Y0064*
X06155Y0064*
X06154Y00639*
X06153Y00639*
X06121*
X06121Y00639*
X0612Y0064*
X0612Y0064*
X06119Y0064*
X06119Y0064*
X06119Y0064*
X06118Y0064*
X06118Y0064*
X06117Y0064*
X06117Y00641*
X06117Y00641*
X06116Y00641*
X06116Y00641*
X06116Y00642*
X06116Y00642*
X06116Y00642*
X06115Y00642*
X06115Y00643*
X06115Y00643*
X06114Y00643*
X06114Y00644*
X06114Y00644*
X06114Y00645*
X06113Y00645*
X06113Y00646*
X06113Y00646*
X06113Y00646*
X06113Y00646*
X06113Y00647*
X06113Y00647*
X06113Y00648*
Y00648*
Y00649*
Y00649*
Y0065*
Y0065*
Y00651*
Y00652*
Y00652*
Y00653*
Y00653*
Y00654*
Y00654*
Y00655*
Y00655*
Y00656*
Y00656*
Y00657*
Y00657*
Y00658*
Y00659*
Y00659*
Y0066*
Y0066*
Y00661*
Y00661*
Y00662*
Y00662*
Y00663*
Y00663*
Y00664*
Y00664*
Y00665*
Y00666*
Y00666*
Y00667*
Y00667*
Y00668*
Y00668*
Y00669*
Y00669*
Y0067*
Y0067*
Y00671*
Y00672*
Y00672*
Y00673*
Y00673*
Y00674*
Y00674*
Y00675*
Y00675*
X06113Y00676*
Y00676*
Y00676*
X06113Y00676*
Y00677*
X06113Y00677*
X06113Y00677*
Y00678*
Y00679*
Y00679*
X06113Y00679*
X06113Y00679*
X06112Y00679*
X06112Y00679*
X06111Y00679*
X06032*
X06031Y00679*
X06031Y00679*
X06031Y00679*
X06031Y00679*
X06031Y00679*
X0603Y00678*
Y00678*
Y00677*
Y00677*
Y00676*
Y00676*
Y00675*
Y00675*
Y00674*
Y00674*
Y00673*
Y00673*
Y00672*
Y00672*
Y00671*
Y0067*
Y0067*
Y00669*
Y00669*
Y00668*
Y00668*
Y00667*
Y00667*
Y00666*
Y00666*
Y00665*
Y00664*
Y00664*
Y00663*
Y00663*
Y00662*
Y00662*
Y00661*
Y00661*
Y0066*
Y0066*
Y00659*
Y00659*
Y00658*
Y00657*
Y00657*
Y00656*
Y00656*
Y00655*
Y00655*
Y00654*
Y00654*
Y00653*
Y00653*
Y00652*
Y00652*
Y00651*
Y0065*
Y0065*
Y00649*
Y00649*
Y00648*
Y00648*
Y00647*
Y00647*
Y00646*
Y00646*
Y00645*
Y00644*
Y00644*
Y00643*
Y00643*
Y00642*
Y00642*
Y00641*
Y00641*
Y0064*
Y0064*
Y00639*
Y00639*
Y00638*
Y00637*
Y00637*
Y00636*
Y00636*
Y00635*
Y00635*
Y00634*
Y00634*
Y00633*
X0603Y00633*
X0603Y00632*
X0603Y00632*
X0603Y00631*
X0603Y00631*
X06029Y0063*
X06029Y0063*
X06028Y0063*
X06028Y00629*
X06027Y00629*
X06027Y00629*
X06026Y00629*
X05946*
X05945Y00629*
X05945Y00629*
X05944Y00629*
X05944Y0063*
X05943Y0063*
X05943Y0063*
X05943Y00631*
X05942Y00631*
X05942Y00632*
X05942Y00632*
X05942Y00633*
X05942Y00633*
Y00634*
Y00634*
Y00635*
Y00635*
Y00636*
Y00636*
Y00637*
Y00637*
Y00638*
Y00639*
Y00639*
Y0064*
Y0064*
Y00641*
Y00641*
Y00642*
Y00642*
Y00643*
Y00643*
Y00644*
Y00644*
Y00645*
Y00646*
Y00646*
Y00647*
Y00647*
Y00648*
Y00648*
Y00649*
Y00649*
Y0065*
Y0065*
Y00651*
Y00652*
Y00652*
Y00653*
Y00653*
Y00654*
Y00654*
Y00655*
Y00655*
Y00656*
Y00656*
Y00657*
Y00657*
Y00658*
Y00659*
Y00659*
Y0066*
Y0066*
Y00661*
Y00661*
Y00662*
Y00662*
Y00663*
Y00663*
Y00664*
Y00664*
Y00665*
Y00666*
Y00666*
Y00667*
Y00667*
Y00668*
Y00668*
Y00669*
Y00669*
Y0067*
Y0067*
Y00671*
Y00672*
Y00672*
Y00673*
Y00673*
Y00674*
Y00674*
Y00675*
Y00675*
Y00676*
Y00676*
Y00677*
Y00677*
Y00678*
Y00679*
Y00679*
Y0068*
Y0068*
Y00681*
Y00681*
Y00682*
X05942Y00682*
X05942Y00683*
X05942Y00683*
X05942Y00684*
X05943Y00684*
X05943Y00685*
X05943Y00685*
X05944Y00685*
X05944Y00685*
X05945Y00686*
X05945Y00686*
X05946Y00686*
X05994*
Y00686*
Y00687*
Y00687*
Y00688*
Y00688*
Y00689*
Y00689*
Y0069*
Y0069*
Y00691*
Y00692*
Y00692*
Y00693*
Y00693*
Y00694*
Y00694*
Y00695*
Y00695*
Y00696*
Y00696*
Y00697*
Y00697*
Y00698*
Y00699*
Y00699*
Y007*
Y007*
Y00701*
Y00701*
Y00702*
Y00702*
Y00703*
Y00703*
Y00704*
Y00704*
Y00705*
Y00706*
Y00706*
Y00707*
Y00707*
Y00708*
Y00708*
Y00709*
Y00709*
Y0071*
Y0071*
Y00711*
Y00712*
Y00712*
Y00713*
Y00713*
Y00714*
Y00714*
Y00715*
Y00715*
Y00716*
Y00716*
Y00717*
Y00717*
Y00718*
Y00719*
Y00719*
Y0072*
Y0072*
Y00721*
Y00721*
Y00722*
Y00722*
Y00723*
Y00723*
Y00724*
Y00725*
Y00725*
Y00726*
Y00726*
Y00727*
Y00727*
Y00728*
Y00728*
Y00729*
Y00729*
Y0073*
Y0073*
Y00731*
Y00732*
Y00732*
Y00733*
Y00733*
Y00734*
Y00734*
Y00735*
Y00735*
Y00736*
Y00736*
Y00737*
Y00737*
X05946*
X05945Y00737*
X05945Y00737*
X05944Y00738*
X05944Y00738*
X05943Y00738*
X05943Y00738*
X05943Y00739*
X05942Y00739*
X05942Y0074*
X05942Y0074*
X05942Y00741*
X05942Y00741*
Y00742*
Y00742*
Y00743*
Y00743*
Y00744*
Y00745*
Y00745*
Y00746*
Y00746*
Y00747*
Y00747*
Y00748*
Y00748*
Y00749*
Y00749*
Y0075*
Y0075*
Y00751*
Y00752*
Y00752*
Y00753*
Y00753*
Y00754*
Y00754*
Y00755*
X05942Y00755*
X05942Y00756*
X05942Y00756*
X05942Y00757*
X05943Y00757*
X05943Y00758*
X05943Y00758*
X05944Y00758*
X05944Y00758*
X05945Y00759*
X05945Y00759*
X05946Y00759*
X05994*
Y00759*
Y0076*
Y0076*
Y00761*
Y00761*
Y00762*
Y00762*
Y00763*
Y00763*
Y00764*
Y00765*
Y00765*
Y00766*
Y00766*
Y00767*
Y00767*
Y00768*
Y00768*
Y00769*
Y00769*
Y0077*
Y0077*
Y00771*
Y00772*
Y00772*
Y00773*
Y00773*
Y00774*
Y00774*
Y00775*
Y00775*
Y00776*
Y00776*
Y00777*
Y00777*
Y00778*
Y00779*
Y00779*
Y0078*
Y0078*
Y00781*
Y00781*
Y00782*
Y00782*
Y00783*
Y00783*
Y00784*
Y00785*
Y00785*
Y00786*
Y00786*
Y00787*
Y00787*
Y00788*
Y00788*
Y00789*
Y00789*
Y0079*
Y0079*
Y00791*
Y00792*
Y00792*
Y00793*
Y00793*
Y00794*
Y00794*
Y00795*
Y00795*
Y00796*
Y00796*
Y00797*
Y00797*
Y00798*
Y00799*
Y00799*
Y008*
Y008*
Y00801*
Y00801*
Y00802*
Y00802*
Y00803*
Y00803*
Y00804*
Y00805*
Y00805*
Y00806*
Y00806*
Y00807*
Y00807*
Y00808*
Y00808*
Y00809*
Y00809*
Y0081*
Y0081*
X05946*
X05946Y0081*
X05945Y0081*
X05945Y00811*
X05944Y00811*
X05944Y00811*
X05944Y00811*
X05943Y00812*
X05943Y00812*
X05943Y00812*
X05942Y00813*
X05942Y00813*
X05942Y00814*
X05942Y00814*
X05942Y00815*
Y00815*
Y00816*
Y00816*
Y00817*
Y00817*
Y00818*
Y00819*
Y00819*
Y0082*
Y0082*
Y00821*
Y00821*
Y00822*
Y00822*
Y00823*
Y00823*
Y00824*
Y00825*
Y00825*
Y00826*
Y00826*
Y00827*
Y00827*
Y00828*
X05942Y00828*
X05942Y00829*
X05942Y00829*
X05942Y0083*
X05943Y0083*
X05943Y00831*
X05943Y00831*
X05944Y00831*
X05944Y00831*
X05945Y00832*
X05945Y00832*
X05946Y00832*
X05994*
Y00832*
Y00833*
Y00833*
Y00834*
Y00834*
Y00835*
Y00835*
Y00836*
Y00836*
Y00837*
Y00837*
Y00838*
Y00839*
Y00839*
Y0084*
Y0084*
Y00841*
Y00841*
Y00842*
Y00842*
Y00843*
Y00843*
Y00844*
Y00845*
Y00845*
Y00846*
Y00846*
Y00847*
Y00847*
Y00848*
Y00848*
Y00849*
Y00849*
Y0085*
Y0085*
Y00851*
Y00852*
Y00852*
Y00853*
Y00853*
Y00854*
Y00854*
Y00855*
Y00855*
Y00856*
Y00856*
Y00857*
Y00857*
Y00858*
Y00859*
Y00859*
Y0086*
Y0086*
Y00861*
Y00861*
Y00862*
Y00862*
Y00863*
Y00863*
Y00864*
Y00865*
Y00865*
Y00866*
Y00866*
Y00867*
Y00867*
Y00868*
Y00868*
Y00869*
Y00869*
Y0087*
Y0087*
Y00871*
Y00872*
Y00872*
Y00873*
Y00873*
Y00874*
Y00874*
Y00875*
Y00875*
Y00876*
Y00876*
Y00877*
Y00877*
Y00878*
Y00879*
Y00879*
Y0088*
Y0088*
Y00881*
Y00881*
Y00882*
Y00882*
Y00883*
Y00883*
Y00884*
X05946*
X05945Y00884*
X05945Y00884*
X05944Y00884*
X05944Y00884*
X05943Y00885*
X05943Y00885*
X05943Y00885*
X05942Y00886*
X05942Y00886*
X05942Y00887*
X05942Y00887*
X05942Y00888*
Y00888*
Y00889*
Y00889*
Y0089*
Y0089*
Y00891*
Y00892*
Y00892*
Y00893*
Y00893*
Y00894*
Y00894*
Y00895*
Y00895*
Y00896*
Y00896*
Y00897*
Y00897*
Y00898*
Y00899*
Y00899*
Y009*
Y009*
Y00901*
X05942Y00901*
X05942Y00902*
X05942Y00902*
X05942Y00903*
X05943Y00903*
X05943Y00904*
X05943Y00904*
X05944Y00904*
X05944Y00904*
X05944Y00905*
X05945Y00905*
X05945Y00905*
X05946Y00905*
X05946Y00905*
X05994*
Y00906*
Y00906*
Y00907*
Y00907*
Y00908*
Y00908*
Y00909*
Y00909*
Y0091*
Y0091*
Y00911*
Y00912*
Y00912*
Y00913*
Y00913*
Y00914*
Y00914*
Y00915*
Y00915*
Y00916*
Y00916*
Y00917*
Y00918*
Y00918*
Y00919*
Y00919*
Y0092*
Y0092*
Y00921*
Y00921*
Y00922*
Y00922*
Y00923*
Y00923*
Y00924*
Y00925*
Y00925*
Y00926*
Y00926*
Y00927*
Y00927*
Y00928*
Y00928*
Y00929*
Y00929*
Y0093*
Y0093*
Y00931*
Y00932*
Y00932*
Y00933*
Y00933*
Y00934*
Y00934*
Y00935*
Y00935*
Y00936*
Y00936*
Y00937*
Y00938*
Y00938*
Y00939*
Y00939*
Y0094*
Y0094*
Y00941*
Y00941*
Y00942*
Y00942*
Y00943*
Y00943*
Y00944*
Y00945*
Y00945*
Y00946*
Y00946*
Y00947*
Y00947*
Y00948*
Y00948*
Y00949*
Y00949*
Y0095*
Y0095*
Y00951*
Y00952*
Y00952*
Y00953*
Y00953*
Y00954*
Y00954*
Y00955*
Y00955*
Y00956*
Y00956*
Y00957*
X05946*
X05945Y00957*
X05945Y00957*
X05944Y00957*
X05944Y00957*
X05943Y00958*
X05943Y00958*
X05943Y00958*
X05942Y00959*
X05942Y00959*
X05942Y0096*
X05942Y0096*
X05942Y00961*
Y00961*
Y00962*
Y00962*
Y00963*
Y00963*
Y00964*
Y00965*
Y00965*
Y00966*
Y00966*
Y00967*
Y00967*
Y00968*
Y00968*
Y00969*
Y00969*
Y0097*
Y0097*
Y00971*
Y00972*
Y00972*
Y00973*
Y00973*
Y00974*
Y00974*
Y00975*
Y00975*
Y00976*
Y00976*
Y00977*
Y00978*
Y00978*
Y00979*
Y00979*
Y0098*
Y0098*
Y00981*
Y00981*
Y00982*
Y00982*
Y00983*
Y00983*
Y00984*
Y00985*
Y00985*
Y00986*
Y00986*
Y00987*
Y00987*
Y00988*
Y00988*
Y00989*
Y00989*
Y0099*
Y0099*
Y00991*
Y00992*
Y00992*
Y00993*
Y00993*
Y00994*
Y00994*
Y00995*
Y00995*
Y00996*
Y00996*
Y00997*
Y00998*
Y00998*
Y00999*
Y00999*
Y01*
Y01*
Y01001*
Y01001*
Y01002*
Y01002*
Y01003*
Y01003*
Y01004*
Y01005*
Y01005*
Y01006*
Y01006*
Y01007*
Y01007*
Y01008*
Y01008*
Y01009*
Y01009*
Y0101*
Y0101*
Y01011*
Y01012*
Y01012*
Y01013*
Y01013*
Y01014*
Y01014*
Y01015*
Y01015*
Y01016*
Y01016*
Y01017*
Y01018*
Y01018*
Y01019*
Y01019*
Y0102*
Y0102*
Y01021*
Y01021*
Y01022*
Y01022*
Y01023*
Y01023*
Y01024*
Y01025*
Y01025*
Y01026*
Y01026*
Y01027*
Y01027*
Y01028*
Y01028*
Y01029*
Y01029*
Y0103*
Y0103*
Y01031*
Y01032*
Y01032*
Y01033*
Y01033*
Y01034*
Y01034*
Y01035*
Y01035*
Y01036*
Y01036*
Y01037*
Y01038*
Y01038*
Y01039*
Y01039*
Y0104*
Y0104*
Y01041*
Y01041*
Y01042*
Y01042*
Y01043*
Y01043*
Y01044*
Y01045*
Y01045*
Y01046*
Y01046*
Y01047*
Y01047*
Y01048*
Y01048*
Y01049*
Y01049*
Y0105*
Y0105*
Y01051*
Y01052*
Y01052*
Y01053*
Y01053*
Y01054*
Y01054*
Y01055*
Y01055*
Y01056*
Y01056*
Y01057*
Y01058*
Y01058*
Y01059*
Y01059*
Y0106*
Y0106*
Y01061*
Y01061*
Y01062*
Y01062*
Y01063*
Y01063*
Y01064*
Y01065*
Y01065*
Y01066*
Y01066*
Y01067*
Y01067*
Y01068*
Y01068*
Y01069*
Y01069*
Y0107*
Y0107*
Y01071*
Y01072*
Y01072*
Y01073*
Y01073*
Y01074*
Y01074*
Y01075*
Y01075*
Y01076*
Y01076*
Y01077*
Y01078*
Y01078*
Y01079*
Y01079*
Y0108*
Y0108*
Y01081*
Y01081*
Y01082*
Y01082*
Y01083*
Y01083*
Y01084*
Y01085*
Y01085*
Y01086*
Y01086*
Y01087*
Y01087*
Y01088*
Y01088*
Y01089*
Y01089*
Y0109*
Y01091*
Y01091*
Y01092*
Y01092*
Y01093*
Y01093*
Y01094*
Y01094*
Y01095*
Y01095*
Y01096*
Y01096*
Y01097*
Y01098*
Y01098*
Y01099*
Y01099*
Y011*
Y011*
Y01101*
Y01101*
Y01102*
Y01102*
Y01103*
Y01103*
Y01104*
Y01105*
Y01105*
Y01106*
Y01106*
Y01107*
Y01107*
Y01108*
Y01108*
Y01109*
Y01109*
Y0111*
Y01111*
Y01111*
Y01112*
Y01112*
Y01113*
Y01113*
Y01114*
Y01114*
Y01115*
Y01115*
Y01116*
Y01116*
Y01117*
Y01118*
Y01118*
Y01119*
Y01119*
Y0112*
Y0112*
Y01121*
Y01121*
Y01122*
Y01122*
Y01123*
Y01123*
Y01124*
Y01125*
Y01125*
Y01126*
Y01126*
Y01127*
Y01127*
Y01128*
Y01128*
Y01129*
Y01129*
Y0113*
Y01131*
Y01131*
Y01132*
Y01132*
Y01133*
Y01133*
Y01134*
Y01134*
Y01135*
Y01135*
Y01136*
Y01136*
Y01137*
Y01138*
Y01138*
Y01139*
Y01139*
Y0114*
Y0114*
Y01141*
Y01141*
Y01142*
Y01142*
Y01143*
Y01143*
Y01144*
Y01145*
Y01145*
Y01146*
Y01146*
Y01147*
Y01147*
Y01148*
Y01148*
Y01149*
Y01149*
Y0115*
Y01151*
Y01151*
Y01152*
Y01152*
Y01153*
Y01153*
Y01154*
Y01154*
Y01155*
Y01155*
Y01156*
Y01156*
Y01157*
Y01158*
Y01158*
Y01159*
Y01159*
Y0116*
Y0116*
Y01161*
Y01161*
Y01162*
Y01162*
Y01163*
Y01163*
Y01164*
Y01165*
Y01165*
Y01166*
Y01166*
Y01167*
Y01167*
Y01168*
Y01168*
Y01169*
Y01169*
Y0117*
Y01171*
Y01171*
Y01172*
Y01172*
Y01173*
Y01173*
Y01174*
Y01174*
Y01175*
Y01175*
Y01176*
Y01176*
X05942Y01177*
X05942Y01177*
X05942Y01178*
X05942Y01178*
X05943Y01179*
X05943Y01179*
X05943Y01179*
X05943Y0118*
X05944Y0118*
X05944Y0118*
X05944Y0118*
X05945Y01181*
X05945Y01181*
X05946Y01181*
X05946Y01181*
X06629*
X06629Y01181*
G37*
G36*
X05971Y00809D02*
X05972Y00809D01*
X05972Y00809*
X05973Y00809*
X05973*
X05974Y00808*
X05974Y00808*
X05975Y00808*
X05975Y00808*
X05976Y00808*
X05976Y00808*
X05976Y00808*
X05977Y00808*
X05977Y00807*
X05977Y00807*
X05977Y00807*
X05978Y00807*
X05978Y00807*
X05979Y00807*
X05979Y00807*
X05979Y00807*
X0598Y00806*
X0598Y00806*
X0598Y00806*
X05981Y00806*
X05981Y00806*
X05982Y00805*
X05982Y00805*
X05982Y00805*
X05982Y00805*
X05983Y00804*
X05983Y00804*
X05984Y00804*
X05984Y00804*
X05984Y00803*
X05984Y00803*
X05985Y00803*
X05985Y00802*
X05985Y00802*
X05985Y00802*
X05986Y00802*
X05986Y00801*
X05986Y00801*
X05986Y00801*
X05987Y00801*
X05987Y00801*
X05987Y008*
X05987Y008*
X05988Y008*
X05988Y00799*
X05988Y00799*
X05989Y00798*
X05989Y00798*
X05989Y00798*
X05989Y00798*
X05989Y00797*
X0599Y00797*
X0599Y00797*
X0599Y00796*
X0599Y00796*
X0599Y00795*
X0599Y00795*
X05991Y00795*
X05991Y00794*
X05991Y00794*
X05991Y00794*
X05991Y00793*
X05991Y00793*
Y00793*
X05992Y00792*
X05992Y00792*
X05992Y00791*
X05992Y00791*
X05992Y0079*
Y0079*
X05992Y0079*
X05992Y0079*
X05992Y00789*
X05993Y00789*
X05993Y00788*
Y00788*
Y00787*
Y00787*
Y00786*
Y00786*
Y00785*
Y00785*
Y00784*
Y00783*
Y00783*
Y00782*
Y00782*
Y00781*
X05993Y00781*
X05992Y0078*
X05992Y0078*
X05992Y00779*
X05992Y00779*
Y00779*
X05992Y00779*
X05992Y00778*
X05992Y00778*
X05992Y00777*
X05991Y00777*
Y00777*
X05991Y00776*
X05991Y00776*
X05991Y00775*
X05991Y00775*
Y00775*
X05991Y00775*
X05991Y00774*
X0599Y00774*
X0599Y00774*
X0599Y00773*
X0599Y00773*
X0599Y00773*
X0599Y00772*
X05989Y00772*
X05989Y00772*
X05989Y00772*
X05989Y00771*
X05989Y00771*
X05988Y0077*
X05988Y0077*
X05988Y0077*
X05988Y0077*
X05988Y0077*
X05987Y00769*
X05987Y00769*
X05987Y00768*
X05987Y00768*
X05986Y00768*
X05986Y00768*
X05986Y00767*
X05985Y00767*
X05985Y00767*
X05985Y00767*
X05985Y00766*
X05984Y00766*
X05984Y00766*
X05984Y00765*
X05983Y00765*
X05983Y00765*
X05983Y00765*
X05982Y00765*
X05982Y00764*
X05981Y00764*
X05981Y00764*
X05981Y00764*
X05981Y00763*
X0598Y00763*
X0598Y00763*
X0598Y00763*
X05979Y00763*
X05979Y00762*
X05978Y00762*
X05978Y00762*
X05978Y00762*
X05978Y00762*
X05977Y00762*
X05977Y00762*
X05977Y00762*
X05976Y00761*
X05976Y00761*
X05975Y00761*
X05975Y00761*
X05974*
X05974Y00761*
X05973Y00761*
X05973Y00761*
X05972Y0076*
X05964*
X05964Y00761*
X05963Y00761*
X05963Y00761*
X05962Y00761*
X05962Y00761*
X05962Y00761*
X05962Y00761*
X05961Y00761*
X05961Y00762*
X05961Y00762*
X05961Y00762*
X0596Y00762*
X05959Y00762*
X05959Y00762*
X05959Y00762*
X05959Y00762*
X05958Y00762*
X05958Y00762*
X05957Y00763*
X05957Y00763*
X05957Y00763*
X05956Y00763*
X05956Y00764*
X05956Y00764*
X05955Y00764*
X05955Y00764*
X05955Y00764*
X05954Y00765*
X05954Y00765*
X05954Y00765*
X05953Y00765*
X05953Y00766*
X05953Y00766*
X05953Y00766*
X05952Y00766*
X05952Y00767*
X05951Y00767*
X05951Y00767*
X05951Y00767*
X05951Y00768*
X0595Y00768*
X0595Y00768*
X0595Y00769*
X05949Y00769*
X05949Y00769*
X05949Y0077*
X05949Y0077*
X05949Y0077*
X05949Y0077*
X05948Y0077*
X05948Y00771*
X05948Y00771*
X05948Y00772*
X05947Y00772*
X05947Y00772*
X05947Y00773*
X05947Y00773*
X05947Y00773*
X05947Y00773*
X05947Y00774*
X05946Y00774*
X05946Y00774*
X05946Y00775*
X05946Y00775*
X05946Y00775*
X05945Y00776*
X05945Y00776*
X05945Y00777*
Y00777*
X05945Y00777*
X05945Y00778*
X05945Y00778*
X05945Y00779*
X05945Y00779*
Y0078*
Y0078*
Y0078*
X05944Y0078*
X05944Y00781*
X05944Y00781*
X05944Y00782*
Y00782*
Y00783*
Y00783*
Y00784*
Y00785*
Y00785*
Y00786*
Y00786*
Y00787*
Y00787*
X05944Y00788*
X05944Y00788*
X05944Y00789*
X05945Y00789*
Y00789*
Y00789*
Y0079*
X05945Y0079*
X05945Y00791*
X05945Y00791*
X05945Y00792*
X05945Y00792*
Y00792*
X05945Y00793*
X05945Y00793*
X05946Y00794*
X05946Y00794*
X05946Y00794*
X05946Y00794*
X05946Y00795*
X05946Y00795*
X05946Y00795*
X05947Y00796*
X05947Y00796*
X05947Y00797*
X05947Y00797*
X05947Y00797*
X05948Y00798*
X05948Y00798*
X05948Y00798*
X05948Y00798*
X05948Y00799*
X05949Y00799*
X05949Y008*
X05949Y008*
X0595Y008*
X0595Y00801*
X0595Y00801*
X0595Y00801*
X0595Y00801*
X05951Y00801*
X05951Y00802*
X05951Y00802*
X05951Y00802*
X05952Y00802*
X05952Y00803*
X05952Y00803*
X05953Y00803*
X05953Y00804*
X05953Y00804*
X05953Y00804*
X05954Y00804*
X05954Y00805*
X05955Y00805*
X05955Y00805*
X05955Y00805*
X05956Y00806*
X05956Y00806*
X05956Y00806*
X05956Y00806*
X05957Y00806*
X05957Y00807*
X05958Y00807*
X05958Y00807*
X05958Y00807*
X05959Y00807*
X05959Y00807*
X0596Y00807*
X0596Y00807*
X0596Y00808*
X05961Y00808*
X05961Y00808*
X05961Y00808*
X05961Y00808*
X05962Y00808*
X05962Y00808*
X05963Y00808*
X05963Y00809*
X05964*
X05964Y00809*
X05965Y00809*
X05965Y00809*
X05966Y00809*
X05971*
X05971Y00809*
G37*
G36*
X05973Y00736D02*
X05974Y00735D01*
X05974Y00735*
X05975Y00735*
X05975Y00735*
X05975*
X05976Y00735*
X05976Y00735*
X05977Y00735*
X05977Y00734*
X05977Y00734*
X05978Y00734*
X05978Y00734*
X05978Y00734*
X05979Y00734*
X05979Y00733*
X0598Y00733*
X0598Y00733*
X0598Y00733*
X05981Y00733*
X05981Y00733*
X05981Y00732*
X05982Y00732*
X05982Y00732*
X05982Y00732*
X05983Y00731*
X05983Y00731*
X05983Y00731*
X05984Y00731*
X05984Y0073*
X05984Y0073*
X05985Y0073*
X05985Y00729*
X05985Y00729*
X05985Y00729*
X05986Y00729*
X05986Y00728*
X05986Y00728*
X05987Y00728*
X05987Y00728*
X05987Y00727*
X05987Y00727*
X05988Y00727*
X05988Y00726*
X05988Y00726*
X05989Y00725*
X05989Y00725*
X05989Y00725*
X05989Y00725*
X05989Y00725*
X05989Y00724*
X0599Y00724*
X0599Y00724*
X0599Y00723*
X0599Y00723*
X0599Y00722*
X0599Y00722*
X05991Y00722*
X05991Y00721*
X05991Y00721*
X05991Y00721*
X05991Y00721*
X05991Y0072*
X05991Y0072*
Y0072*
X05992Y00719*
X05992Y00719*
X05992Y00719*
X05992Y00718*
X05992Y00717*
Y00717*
Y00717*
X05992Y00717*
X05992Y00716*
X05992Y00716*
X05993Y00715*
X05993Y00715*
Y00714*
Y00714*
Y00713*
Y00713*
Y00712*
Y00712*
Y00711*
Y0071*
Y0071*
Y00709*
Y00709*
Y00708*
X05993Y00708*
X05992Y00707*
X05992Y00707*
X05992Y00706*
X05992*
Y00706*
Y00706*
X05992Y00705*
X05992Y00705*
X05992Y00704*
X05992Y00704*
X05991Y00704*
Y00703*
X05991Y00703*
X05991Y00702*
X05991Y00702*
X05991Y00702*
X05991Y00701*
X0599Y00701*
X0599Y00701*
X0599Y007*
X0599Y007*
X0599Y007*
X0599Y00699*
X0599Y00699*
X05989Y00699*
X05989Y00698*
X05989Y00698*
X05989Y00698*
X05989Y00698*
X05988Y00697*
X05988Y00697*
X05988Y00696*
X05987Y00696*
X05987Y00696*
X05987Y00695*
X05987Y00695*
X05986Y00695*
X05986Y00695*
X05986Y00694*
X05985Y00694*
X05985Y00694*
X05985Y00694*
X05985Y00693*
X05984Y00693*
X05984Y00693*
X05984Y00692*
X05983Y00692*
X05983Y00692*
X05983Y00692*
X05982Y00692*
X05982Y00691*
X05982Y00691*
X05981Y00691*
X05981Y00691*
X05981Y0069*
X0598Y0069*
X0598Y0069*
X0598Y0069*
X05979Y0069*
X05979Y00689*
X05978Y00689*
X05978Y00689*
X05978Y00689*
X05977Y00689*
X05977Y00689*
X05977Y00689*
X05977Y00689*
X05976Y00688*
X05976Y00688*
X05975Y00688*
X05975*
X05975Y00688*
X05974Y00688*
X05974Y00688*
X05973Y00688*
X05973Y00688*
X05964*
X05963Y00688*
X05963Y00688*
X05962Y00688*
X05962Y00688*
X05962Y00688*
X05962*
X05961Y00688*
X05961Y00688*
X0596Y00689*
X0596Y00689*
X0596Y00689*
X05959Y00689*
X05959Y00689*
X05958Y00689*
X05958Y00689*
X05958Y00689*
X05957Y0069*
X05957Y0069*
X05957Y0069*
X05956Y0069*
X05956Y0069*
X05956Y00691*
X05955Y00691*
X05955Y00691*
X05954Y00691*
X05954Y00692*
X05954Y00692*
X05954Y00692*
X05954Y00692*
X05954Y00692*
X05953Y00692*
X05953Y00693*
X05952Y00693*
X05952Y00693*
X05952Y00694*
X05951Y00694*
X05951Y00694*
X05951Y00694*
X05951Y00694*
X05951Y00695*
X0595Y00695*
X0595Y00695*
X0595Y00695*
X0595Y00696*
X05949Y00696*
X05949Y00697*
X05949Y00697*
X05949Y00697*
X05948Y00697*
X05948Y00698*
X05948Y00698*
X05948Y00699*
X05947Y00699*
X05947Y00699*
X05947Y007*
X05947Y007*
X05947Y007*
X05947Y00701*
X05946Y00701*
X05946Y00701*
X05946Y00702*
X05946Y00702*
X05946Y00702*
X05945Y00703*
X05945Y00703*
X05945Y00704*
Y00704*
X05945Y00704*
X05945Y00705*
X05945Y00705*
X05945Y00706*
X05945Y00706*
Y00707*
Y00707*
X05944Y00707*
X05944Y00708*
X05944Y00708*
X05944Y00709*
Y00709*
Y0071*
Y0071*
Y00711*
Y00712*
Y00712*
Y00713*
Y00713*
Y00714*
Y00714*
X05944Y00715*
X05944Y00715*
X05944Y00716*
X05945Y00716*
Y00716*
Y00717*
X05945Y00717*
X05945Y00718*
X05945Y00718*
X05945Y00719*
X05945Y00719*
Y00719*
X05945Y0072*
X05945Y0072*
X05946Y00721*
X05946Y00721*
X05946Y00721*
X05946Y00722*
X05946Y00722*
X05947Y00722*
X05947Y00723*
X05947Y00723*
X05947Y00723*
X05947Y00724*
X05947Y00724*
X05948Y00724*
X05948Y00725*
X05948Y00725*
X05948Y00726*
X05949Y00726*
X05949Y00726*
X05949Y00727*
X05949Y00727*
X0595Y00727*
X0595Y00728*
X0595Y00728*
X0595Y00728*
X05951Y00728*
X05951Y00729*
X05951Y00729*
X05951Y00729*
X05952Y00729*
X05952Y0073*
X05952Y0073*
X05953Y0073*
X05953Y00731*
X05953Y00731*
X05954Y00731*
X05954Y00731*
X05954Y00732*
X05954Y00732*
X05955Y00732*
X05955Y00732*
X05956Y00733*
X05956Y00733*
X05956Y00733*
X05957Y00733*
X05957Y00733*
X05957Y00733*
X05958Y00734*
X05958Y00734*
X05958Y00734*
X05959Y00734*
X05959Y00734*
X0596Y00734*
X0596*
X0596Y00734*
X05961Y00735*
X05961Y00735*
X05962Y00735*
X05962*
X05962Y00735*
X05962Y00735*
X05963Y00735*
X05963Y00736*
X05964Y00736*
X05973*
X05973Y00736*
G37*
G36*
X05895Y01181D02*
X05895Y01181D01*
X05896Y01181*
X05896Y0118*
Y0118*
X05899*
X059Y0118*
X059Y0118*
X05901Y0118*
X05901Y0118*
Y0118*
X05902*
X05902Y0118*
X05903Y0118*
X05903Y0118*
X05904Y01179*
Y01179*
X05904*
X05904Y01179*
X05905Y01179*
X05905Y01179*
X05906Y01179*
X05906Y01179*
X05906Y01179*
X05907Y01178*
X05907Y01178*
X05907*
X05907Y01178*
X05908Y01178*
X05908Y01178*
X05909Y01178*
X05909Y01177*
X0591Y01177*
X0591Y01177*
X0591Y01177*
X05911Y01177*
X05911Y01176*
X05911Y01176*
X05912Y01176*
X05912Y01176*
X05912Y01176*
X05913Y01176*
X05913Y01175*
X05914Y01175*
X05914Y01175*
X05914Y01175*
X05914Y01175*
X05915Y01174*
X05915Y01174*
X05915Y01174*
X05916Y01173*
X05916Y01173*
X05916Y01173*
X05917Y01173*
X05917Y01173*
X05917Y01172*
X05918Y01172*
X05918Y01172*
X05918Y01171*
X05918Y01171*
X05919Y01171*
X05919Y01171*
X05919Y0117*
X0592Y0117*
X0592Y0117*
X0592Y0117*
X0592Y01169*
X05921Y01169*
X05921Y01169*
X05921Y01169*
X05921Y01168*
X05921Y01168*
X05922Y01168*
X05922Y01168*
X05922Y01167*
X05923Y01167*
X05923Y01166*
X05923Y01166*
X05923Y01166*
X05923Y01166*
X05924Y01165*
X05924Y01165*
X05924Y01164*
X05924Y01164*
X05924Y01164*
X05925Y01164*
X05925Y01163*
X05925Y01163*
X05925Y01163*
X05926Y01162*
X05926Y01162*
X05926Y01161*
X05926Y01161*
X05926Y01161*
X05926Y0116*
X05927Y0116*
X05927Y0116*
X05927Y01159*
X05927Y01159*
X05927Y01159*
X05927Y01159*
X05928Y01158*
X05928Y01158*
X05928Y01157*
X05928Y01157*
X05928Y01157*
X05928Y01157*
X05928Y01156*
X05929Y01156*
X05929Y01155*
X05929Y01155*
X05929Y01154*
Y01154*
Y01154*
X05929Y01154*
X05929Y01153*
X05929Y01153*
X05929Y01152*
Y01152*
Y01151*
X0593Y01151*
X0593Y0115*
X0593Y0115*
X0593Y01149*
Y01149*
Y01148*
Y01148*
Y01147*
Y01147*
Y01146*
Y01146*
Y01145*
Y01145*
Y01144*
Y01143*
Y01143*
Y01142*
Y01142*
Y01141*
Y01141*
Y0114*
Y0114*
Y01139*
Y01139*
Y01138*
Y01138*
Y01137*
Y01136*
Y01136*
Y01135*
Y01135*
Y01134*
Y01134*
Y01133*
Y01133*
Y01132*
Y01132*
Y01131*
Y01131*
Y0113*
Y01129*
Y01129*
Y01128*
Y01128*
Y01127*
Y01127*
Y01126*
Y01126*
Y01125*
Y01125*
Y01124*
Y01123*
Y01123*
Y01122*
Y01122*
Y01121*
Y01121*
Y0112*
Y0112*
Y01119*
Y01119*
Y01118*
Y01118*
Y01117*
Y01116*
Y01116*
Y01115*
Y01115*
Y01114*
Y01114*
Y01113*
Y01113*
Y01112*
Y01112*
Y01111*
Y01111*
Y0111*
Y01109*
Y01109*
Y01108*
Y01108*
Y01107*
Y01107*
Y01106*
Y01106*
Y01105*
Y01105*
Y01104*
Y01103*
Y01103*
Y01102*
Y01102*
Y01101*
Y01101*
Y011*
Y011*
Y01099*
Y01099*
Y01098*
Y01098*
Y01097*
Y01096*
Y01096*
Y01095*
Y01095*
Y01094*
Y01094*
Y01093*
Y01093*
Y01092*
Y01092*
Y01091*
Y01091*
Y0109*
Y01089*
Y01089*
Y01088*
Y01088*
Y01087*
Y01087*
Y01086*
Y01086*
Y01085*
Y01085*
Y01084*
Y01083*
Y01083*
Y01082*
Y01082*
Y01081*
Y01081*
Y0108*
Y0108*
Y01079*
Y01079*
Y01078*
Y01078*
Y01077*
Y01076*
Y01076*
Y01075*
Y01075*
Y01074*
Y01074*
Y01073*
Y01073*
Y01072*
Y01072*
Y01071*
Y0107*
Y0107*
Y01069*
Y01069*
Y01068*
Y01068*
Y01067*
Y01067*
Y01066*
Y01066*
Y01065*
Y01065*
Y01064*
Y01063*
Y01063*
Y01062*
Y01062*
Y01061*
Y01061*
Y0106*
Y0106*
Y01059*
Y01059*
Y01058*
Y01058*
Y01057*
Y01056*
Y01056*
Y01055*
Y01055*
Y01054*
Y01054*
Y01053*
Y01053*
Y01052*
Y01052*
Y01051*
Y0105*
Y0105*
Y01049*
Y01049*
Y01048*
Y01048*
Y01047*
Y01047*
Y01046*
Y01046*
Y01045*
Y01045*
Y01044*
Y01043*
Y01043*
Y01042*
Y01042*
Y01041*
Y01041*
Y0104*
Y0104*
Y01039*
Y01039*
Y01038*
Y01038*
Y01037*
Y01036*
Y01036*
Y01035*
Y01035*
Y01034*
Y01034*
Y01033*
Y01033*
Y01032*
Y01032*
Y01031*
Y0103*
Y0103*
Y01029*
Y01029*
Y01028*
Y01028*
Y01027*
Y01027*
Y01026*
Y01026*
Y01025*
Y01025*
Y01024*
Y01023*
Y01023*
Y01022*
Y01022*
Y01021*
Y01021*
Y0102*
Y0102*
Y01019*
Y01019*
Y01018*
Y01018*
Y01017*
Y01016*
Y01016*
Y01015*
Y01015*
Y01014*
Y01014*
Y01013*
Y01013*
Y01012*
Y01012*
Y01011*
Y0101*
Y0101*
Y01009*
Y01009*
Y01008*
Y01008*
Y01007*
Y01007*
Y01006*
Y01006*
Y01005*
Y01005*
Y01004*
Y01003*
Y01003*
Y01002*
Y01002*
Y01001*
Y01001*
Y01*
Y01*
Y00999*
Y00999*
Y00998*
Y00998*
Y00997*
Y00996*
Y00996*
Y00995*
Y00995*
Y00994*
Y00994*
Y00993*
Y00993*
Y00992*
Y00992*
Y00991*
Y0099*
Y0099*
Y00989*
Y00989*
Y00988*
Y00988*
Y00987*
Y00987*
Y00986*
Y00986*
Y00985*
Y00985*
Y00984*
Y00983*
Y00983*
Y00982*
Y00982*
Y00981*
Y00981*
Y0098*
Y0098*
Y00979*
Y00979*
Y00978*
Y00978*
Y00977*
Y00976*
Y00976*
Y00975*
Y00975*
Y00974*
Y00974*
Y00973*
Y00973*
Y00972*
Y00972*
Y00971*
Y0097*
Y0097*
Y00969*
Y00969*
Y00968*
Y00968*
Y00967*
Y00967*
Y00966*
Y00966*
Y00965*
Y00965*
Y00964*
Y00963*
Y00963*
Y00962*
Y00962*
Y00961*
Y00961*
Y0096*
Y0096*
Y00959*
Y00959*
Y00958*
Y00958*
Y00957*
Y00956*
Y00956*
Y00955*
Y00955*
Y00954*
Y00954*
Y00953*
Y00953*
Y00952*
Y00952*
Y00951*
Y0095*
Y0095*
Y00949*
Y00949*
Y00948*
Y00948*
Y00947*
Y00947*
Y00946*
Y00946*
Y00945*
Y00945*
Y00944*
Y00943*
Y00943*
Y00942*
Y00942*
Y00941*
Y00941*
Y0094*
Y0094*
Y00939*
Y00939*
Y00938*
Y00938*
Y00937*
Y00936*
Y00936*
Y00935*
Y00935*
Y00934*
Y00934*
Y00933*
Y00933*
Y00932*
Y00932*
Y00931*
Y0093*
Y0093*
Y00929*
Y00929*
Y00928*
Y00928*
Y00927*
Y00927*
Y00926*
Y00926*
Y00925*
Y00925*
Y00924*
Y00923*
Y00923*
Y00922*
Y00922*
Y00921*
Y00921*
Y0092*
Y0092*
Y00919*
Y00919*
Y00918*
Y00918*
Y00917*
Y00916*
Y00916*
Y00915*
Y00915*
Y00914*
Y00914*
Y00913*
Y00913*
Y00912*
Y00912*
Y00911*
Y0091*
Y0091*
Y00909*
Y00909*
Y00908*
Y00908*
Y00907*
Y00907*
Y00906*
Y00906*
Y00905*
Y00905*
Y00904*
Y00903*
Y00903*
Y00902*
Y00902*
Y00901*
Y00901*
Y009*
Y009*
Y00899*
Y00899*
Y00898*
Y00897*
Y00897*
Y00896*
Y00896*
Y00895*
Y00895*
Y00894*
Y00894*
Y00893*
Y00893*
Y00892*
Y00892*
Y00891*
Y0089*
Y0089*
Y00889*
Y00889*
Y00888*
Y00888*
Y00887*
Y00887*
Y00886*
Y00886*
Y00885*
Y00885*
Y00884*
Y00883*
Y00883*
Y00882*
Y00882*
Y00881*
Y00881*
Y0088*
Y0088*
Y00879*
Y00879*
Y00878*
Y00877*
Y00877*
Y00876*
Y00876*
Y00875*
Y00875*
Y00874*
Y00874*
Y00873*
Y00873*
Y00872*
Y00872*
Y00871*
Y0087*
Y0087*
Y00869*
Y00869*
Y00868*
Y00868*
Y00867*
Y00867*
Y00866*
Y00866*
Y00865*
Y00865*
Y00864*
Y00863*
Y00863*
Y00862*
Y00862*
Y00861*
Y00861*
Y0086*
Y0086*
Y00859*
Y00859*
Y00858*
Y00857*
Y00857*
Y00856*
Y00856*
Y00855*
Y00855*
Y00854*
Y00854*
Y00853*
Y00853*
Y00852*
Y00852*
Y00851*
Y0085*
Y0085*
Y00849*
Y00849*
Y00848*
Y00848*
Y00847*
Y00847*
Y00846*
Y00846*
Y00845*
Y00845*
Y00844*
Y00843*
Y00843*
Y00842*
Y00842*
Y00841*
Y00841*
Y0084*
Y0084*
Y00839*
Y00839*
Y00838*
Y00837*
Y00837*
Y00836*
Y00836*
Y00835*
Y00835*
Y00834*
Y00834*
Y00833*
Y00833*
Y00832*
Y00832*
Y00831*
Y0083*
Y0083*
Y00829*
Y00829*
Y00828*
Y00828*
Y00827*
Y00827*
Y00826*
Y00826*
Y00825*
Y00825*
Y00824*
Y00823*
Y00823*
Y00822*
Y00822*
Y00821*
Y00821*
Y0082*
Y0082*
Y00819*
Y00819*
Y00818*
Y00817*
Y00817*
Y00816*
Y00816*
Y00815*
Y00815*
Y00814*
Y00814*
Y00813*
Y00813*
Y00812*
Y00812*
Y00811*
Y0081*
Y0081*
Y00809*
Y00809*
Y00808*
Y00808*
Y00807*
Y00807*
Y00806*
Y00806*
Y00805*
Y00805*
Y00804*
Y00803*
Y00803*
Y00802*
Y00802*
Y00801*
Y00801*
Y008*
Y008*
Y00799*
Y00799*
Y00798*
Y00797*
Y00797*
Y00796*
Y00796*
Y00795*
Y00795*
Y00794*
Y00794*
Y00793*
Y00793*
Y00792*
Y00792*
Y00791*
Y0079*
Y0079*
Y00789*
Y00789*
Y00788*
Y00788*
Y00787*
Y00787*
Y00786*
Y00786*
Y00785*
Y00785*
Y00784*
Y00783*
Y00783*
Y00782*
Y00782*
Y00781*
Y00781*
Y0078*
Y0078*
Y00779*
Y00779*
Y00778*
Y00777*
Y00777*
Y00776*
Y00776*
Y00775*
Y00775*
Y00774*
Y00774*
Y00773*
Y00773*
Y00772*
Y00772*
Y00771*
Y0077*
Y0077*
Y00769*
Y00769*
Y00768*
Y00768*
Y00767*
Y00767*
Y00766*
Y00766*
Y00765*
Y00765*
Y00764*
Y00763*
Y00763*
Y00762*
Y00762*
Y00761*
Y00761*
Y0076*
Y0076*
Y00759*
Y00759*
Y00758*
Y00757*
Y00757*
Y00756*
Y00756*
Y00755*
Y00755*
Y00754*
Y00754*
Y00753*
Y00753*
Y00752*
Y00752*
Y00751*
Y0075*
Y0075*
Y00749*
Y00749*
Y00748*
Y00748*
Y00747*
Y00747*
Y00746*
Y00746*
Y00745*
Y00745*
Y00744*
Y00743*
Y00743*
Y00742*
Y00742*
Y00741*
Y00741*
Y0074*
Y0074*
Y00739*
Y00739*
Y00738*
Y00737*
Y00737*
Y00736*
Y00736*
Y00735*
Y00735*
Y00734*
Y00734*
Y00733*
Y00733*
Y00732*
Y00732*
Y00731*
Y0073*
Y0073*
Y00729*
Y00729*
Y00728*
Y00728*
Y00727*
Y00727*
Y00726*
Y00726*
Y00725*
Y00725*
Y00724*
Y00723*
Y00723*
Y00722*
Y00722*
Y00721*
Y00721*
Y0072*
Y0072*
Y00719*
Y00719*
Y00718*
Y00717*
Y00717*
Y00716*
Y00716*
Y00715*
Y00715*
Y00714*
Y00714*
Y00713*
Y00713*
Y00712*
Y00712*
Y00711*
Y0071*
Y0071*
Y00709*
Y00709*
Y00708*
Y00708*
Y00707*
Y00707*
Y00706*
Y00706*
Y00705*
Y00704*
Y00704*
Y00703*
Y00703*
Y00702*
Y00702*
Y00701*
Y00701*
Y007*
Y007*
Y00699*
Y00699*
Y00698*
Y00697*
Y00697*
Y00696*
Y00696*
Y00695*
Y00695*
Y00694*
Y00694*
Y00693*
Y00693*
Y00692*
Y00692*
Y00691*
Y0069*
Y0069*
Y00689*
Y00689*
Y00688*
Y00688*
Y00687*
Y00687*
Y00686*
Y00686*
Y00685*
Y00684*
Y00684*
Y00683*
Y00683*
Y00682*
Y00682*
Y00681*
Y00681*
Y0068*
Y0068*
Y00679*
Y00679*
Y00678*
Y00677*
Y00677*
Y00676*
Y00676*
Y00675*
Y00675*
Y00674*
Y00674*
Y00673*
Y00673*
Y00672*
Y00672*
Y00671*
Y0067*
Y0067*
Y00669*
Y00669*
Y00668*
Y00668*
Y00667*
Y00667*
Y00666*
Y00666*
Y00665*
Y00664*
Y00664*
Y00663*
Y00663*
Y00662*
Y00662*
Y00661*
Y00661*
Y0066*
Y0066*
Y00659*
Y00659*
Y00658*
Y00657*
Y00657*
Y00656*
Y00656*
Y00655*
Y00655*
Y00654*
Y00654*
Y00653*
Y00653*
Y00652*
Y00652*
Y00651*
Y0065*
Y0065*
Y00649*
Y00649*
Y00648*
Y00648*
Y00647*
Y00647*
Y00646*
Y00646*
Y00645*
Y00644*
Y00644*
Y00643*
Y00643*
Y00642*
Y00642*
Y00641*
Y00641*
Y0064*
Y0064*
Y00639*
Y00639*
Y00638*
Y00637*
Y00637*
Y00636*
Y00636*
Y00635*
Y00635*
Y00634*
Y00634*
Y00633*
Y00633*
Y00632*
Y00632*
Y00631*
Y0063*
Y0063*
Y00629*
Y00629*
Y00628*
Y00628*
Y00627*
Y00627*
Y00626*
Y00626*
Y00625*
Y00624*
Y00624*
Y00623*
Y00623*
Y00622*
Y00622*
Y00621*
Y00621*
Y0062*
Y0062*
Y00619*
Y00619*
Y00618*
Y00617*
Y00617*
Y00616*
Y00616*
Y00615*
Y00615*
Y00614*
Y00614*
Y00613*
Y00613*
Y00612*
Y00612*
Y00611*
Y0061*
Y0061*
Y00609*
Y00609*
Y00608*
Y00608*
Y00607*
Y00607*
Y00606*
Y00606*
Y00605*
Y00604*
Y00604*
Y00603*
Y00603*
Y00602*
Y00602*
Y00601*
Y00601*
Y006*
Y006*
Y00599*
Y00599*
Y00598*
Y00597*
Y00597*
Y00596*
Y00596*
Y00595*
Y00595*
Y00594*
Y00594*
Y00593*
Y00593*
Y00592*
Y00592*
Y00591*
Y0059*
Y0059*
Y00589*
Y00589*
Y00588*
Y00588*
Y00587*
Y00587*
Y00586*
Y00586*
Y00585*
Y00584*
Y00584*
Y00583*
Y00583*
Y00582*
Y00582*
Y00581*
Y00581*
Y0058*
Y0058*
Y00579*
Y00579*
Y00578*
Y00577*
Y00577*
Y00576*
Y00576*
Y00575*
Y00575*
Y00574*
Y00574*
Y00573*
Y00573*
Y00572*
Y00572*
Y00571*
Y0057*
Y0057*
Y00569*
Y00569*
Y00568*
Y00568*
Y00567*
Y00567*
Y00566*
Y00566*
Y00565*
Y00564*
Y00564*
Y00563*
Y00563*
Y00562*
Y00562*
Y00561*
Y00561*
Y0056*
Y0056*
Y00559*
X0593Y00559*
X0593Y00558*
X0593Y00558*
X05929Y00557*
X05929Y00557*
X05929Y00556*
X05928Y00556*
X05928Y00556*
X05927Y00555*
X05927Y00555*
X05926Y00555*
X05926Y00555*
X05906*
X05905Y00555*
X05905Y00555*
X05904Y00555*
X05904Y00556*
X05903Y00556*
X05903Y00556*
X05903Y00557*
X05902Y00557*
X05902Y00558*
X05902Y00558*
X05902Y00559*
X05902Y00559*
Y0056*
Y0056*
Y00561*
Y00561*
Y00562*
Y00562*
Y00563*
Y00563*
Y00564*
Y00564*
Y00565*
Y00566*
Y00566*
Y00567*
Y00567*
Y00568*
Y00568*
Y00569*
Y00569*
Y0057*
Y0057*
Y00571*
Y00572*
Y00572*
Y00573*
Y00573*
Y00574*
Y00574*
Y00575*
Y00575*
Y00576*
Y00576*
Y00577*
Y00577*
Y00578*
Y00579*
Y00579*
Y0058*
Y0058*
Y00581*
Y00581*
Y00582*
Y00582*
Y00583*
Y00583*
Y00584*
Y00584*
Y00585*
Y00586*
Y00586*
Y00587*
Y00587*
Y00588*
Y00588*
Y00589*
Y00589*
Y0059*
Y0059*
Y00591*
Y00592*
Y00592*
Y00593*
Y00593*
Y00594*
Y00594*
Y00595*
Y00595*
Y00596*
Y00596*
Y00597*
Y00597*
Y00598*
Y00599*
Y00599*
Y006*
Y006*
Y00601*
Y00601*
Y00602*
Y00602*
Y00603*
Y00603*
Y00604*
Y00604*
Y00605*
Y00606*
Y00606*
Y00607*
Y00607*
Y00608*
Y00608*
Y00609*
Y00609*
Y0061*
Y0061*
Y00611*
Y00612*
Y00612*
Y00613*
Y00613*
Y00614*
Y00614*
Y00615*
Y00615*
Y00616*
Y00616*
Y00617*
Y00617*
Y00618*
Y00619*
Y00619*
Y0062*
Y0062*
Y00621*
Y00621*
Y00622*
Y00622*
Y00623*
Y00623*
Y00624*
Y00624*
Y00625*
Y00626*
Y00626*
Y00627*
Y00627*
Y00628*
Y00628*
Y00629*
Y00629*
Y0063*
Y0063*
Y00631*
Y00632*
Y00632*
Y00633*
Y00633*
Y00634*
Y00634*
Y00635*
Y00635*
Y00636*
Y00636*
Y00637*
Y00637*
Y00638*
Y00639*
Y00639*
Y0064*
Y0064*
Y00641*
Y00641*
Y00642*
Y00642*
Y00643*
Y00643*
Y00644*
Y00644*
Y00645*
Y00646*
Y00646*
Y00647*
Y00647*
Y00648*
Y00648*
Y00649*
Y00649*
Y0065*
Y0065*
Y00651*
Y00652*
Y00652*
Y00653*
Y00653*
Y00654*
Y00654*
Y00655*
Y00655*
Y00656*
Y00656*
Y00657*
Y00657*
Y00658*
Y00659*
Y00659*
Y0066*
Y0066*
Y00661*
Y00661*
Y00662*
Y00662*
Y00663*
Y00663*
Y00664*
Y00664*
Y00665*
Y00666*
Y00666*
Y00667*
Y00667*
Y00668*
Y00668*
Y00669*
Y00669*
Y0067*
Y0067*
Y00671*
Y00672*
Y00672*
Y00673*
Y00673*
Y00674*
Y00674*
Y00675*
Y00675*
Y00676*
Y00676*
Y00677*
Y00677*
Y00678*
Y00679*
Y00679*
Y0068*
Y0068*
Y00681*
Y00681*
Y00682*
Y00682*
Y00683*
Y00683*
Y00684*
Y00684*
Y00685*
Y00686*
Y00686*
Y00687*
Y00687*
Y00688*
Y00688*
Y00689*
Y00689*
Y0069*
Y0069*
Y00691*
Y00692*
Y00692*
Y00693*
Y00693*
Y00694*
Y00694*
Y00695*
Y00695*
Y00696*
Y00696*
Y00697*
Y00697*
Y00698*
Y00699*
Y00699*
Y007*
Y007*
Y00701*
Y00701*
Y00702*
Y00702*
Y00703*
Y00703*
Y00704*
Y00704*
Y00705*
Y00706*
Y00706*
Y00707*
Y00707*
Y00708*
Y00708*
Y00709*
Y00709*
Y0071*
Y0071*
Y00711*
Y00712*
Y00712*
Y00713*
Y00713*
Y00714*
Y00714*
Y00715*
Y00715*
Y00716*
Y00716*
Y00717*
Y00717*
Y00718*
Y00719*
Y00719*
Y0072*
Y0072*
Y00721*
Y00721*
Y00722*
Y00722*
Y00723*
Y00723*
Y00724*
Y00725*
Y00725*
Y00726*
Y00726*
Y00727*
Y00727*
Y00728*
Y00728*
Y00729*
Y00729*
Y0073*
Y0073*
Y00731*
Y00732*
Y00732*
Y00733*
Y00733*
Y00734*
Y00734*
Y00735*
Y00735*
Y00736*
Y00736*
Y00737*
Y00737*
Y00738*
Y00739*
Y00739*
Y0074*
Y0074*
Y00741*
Y00741*
Y00742*
Y00742*
Y00743*
Y00743*
Y00744*
Y00745*
Y00745*
Y00746*
Y00746*
Y00747*
Y00747*
Y00748*
Y00748*
Y00749*
Y00749*
Y0075*
Y0075*
Y00751*
Y00752*
Y00752*
Y00753*
Y00753*
Y00754*
Y00754*
Y00755*
Y00755*
Y00756*
Y00756*
Y00757*
Y00757*
Y00758*
Y00759*
Y00759*
Y0076*
Y0076*
Y00761*
Y00761*
Y00762*
Y00762*
Y00763*
Y00763*
Y00764*
Y00765*
Y00765*
Y00766*
Y00766*
Y00767*
Y00767*
Y00768*
Y00768*
Y00769*
Y00769*
Y0077*
Y0077*
Y00771*
Y00772*
Y00772*
Y00773*
Y00773*
Y00774*
Y00774*
Y00775*
Y00775*
Y00776*
Y00776*
Y00777*
Y00777*
Y00778*
Y00779*
Y00779*
Y0078*
Y0078*
Y00781*
Y00781*
Y00782*
Y00782*
Y00783*
Y00783*
Y00784*
Y00785*
Y00785*
Y00786*
Y00786*
Y00787*
Y00787*
Y00788*
Y00788*
Y00789*
Y00789*
Y0079*
Y0079*
Y00791*
Y00792*
Y00792*
Y00793*
Y00793*
Y00794*
Y00794*
Y00795*
Y00795*
Y00796*
Y00796*
Y00797*
Y00797*
Y00798*
Y00799*
Y00799*
Y008*
Y008*
Y00801*
Y00801*
Y00802*
Y00802*
Y00803*
Y00803*
Y00804*
Y00805*
Y00805*
Y00806*
Y00806*
Y00807*
Y00807*
Y00808*
Y00808*
Y00809*
Y00809*
Y0081*
Y0081*
Y00811*
Y00812*
Y00812*
Y00813*
Y00813*
Y00814*
Y00814*
Y00815*
Y00815*
Y00816*
Y00816*
Y00817*
Y00817*
Y00818*
Y00819*
Y00819*
Y0082*
Y0082*
Y00821*
Y00821*
Y00822*
Y00822*
Y00823*
Y00823*
Y00824*
Y00825*
Y00825*
Y00826*
Y00826*
Y00827*
Y00827*
Y00828*
Y00828*
Y00829*
Y00829*
Y0083*
Y0083*
Y00831*
Y00832*
Y00832*
Y00833*
Y00833*
Y00834*
Y00834*
Y00835*
Y00835*
Y00836*
Y00836*
Y00837*
Y00837*
Y00838*
Y00839*
Y00839*
Y0084*
Y0084*
Y00841*
Y00841*
Y00842*
Y00842*
Y00843*
Y00843*
Y00844*
Y00845*
Y00845*
Y00846*
Y00846*
Y00847*
Y00847*
Y00848*
Y00848*
Y00849*
Y00849*
Y0085*
Y0085*
Y00851*
Y00852*
Y00852*
Y00853*
Y00853*
Y00854*
Y00854*
Y00855*
Y00855*
Y00856*
Y00856*
Y00857*
Y00857*
Y00858*
Y00859*
Y00859*
Y0086*
Y0086*
Y00861*
Y00861*
Y00862*
Y00862*
Y00863*
Y00863*
Y00864*
Y00865*
Y00865*
Y00866*
Y00866*
Y00867*
Y00867*
Y00868*
Y00868*
Y00869*
Y00869*
Y0087*
Y0087*
Y00871*
Y00872*
Y00872*
Y00873*
Y00873*
Y00874*
Y00874*
Y00875*
Y00875*
Y00876*
Y00876*
Y00877*
Y00877*
Y00878*
Y00879*
Y00879*
Y0088*
Y0088*
Y00881*
Y00881*
Y00882*
Y00882*
Y00883*
Y00883*
Y00884*
Y00885*
Y00885*
Y00886*
Y00886*
Y00887*
Y00887*
Y00888*
Y00888*
Y00889*
Y00889*
Y0089*
Y0089*
Y00891*
Y00892*
Y00892*
Y00893*
Y00893*
Y00894*
Y00894*
Y00895*
Y00895*
Y00896*
Y00896*
Y00897*
Y00897*
Y00898*
Y00899*
Y00899*
Y009*
Y009*
Y00901*
Y00901*
Y00902*
Y00902*
Y00903*
Y00903*
Y00904*
Y00905*
Y00905*
Y00906*
Y00906*
Y00907*
Y00907*
Y00908*
Y00908*
Y00909*
Y00909*
Y0091*
Y0091*
Y00911*
Y00912*
Y00912*
Y00913*
Y00913*
Y00914*
Y00914*
Y00915*
Y00915*
Y00916*
Y00916*
Y00917*
Y00918*
Y00918*
Y00919*
Y00919*
Y0092*
Y0092*
Y00921*
Y00921*
Y00922*
Y00922*
Y00923*
Y00923*
Y00924*
Y00925*
Y00925*
Y00926*
Y00926*
Y00927*
Y00927*
Y00928*
Y00928*
Y00929*
Y00929*
Y0093*
Y0093*
Y00931*
Y00932*
Y00932*
Y00933*
Y00933*
Y00934*
Y00934*
Y00935*
Y00935*
Y00936*
Y00936*
Y00937*
Y00938*
Y00938*
Y00939*
Y00939*
Y0094*
Y0094*
Y00941*
Y00941*
Y00942*
Y00942*
Y00943*
Y00943*
Y00944*
Y00945*
Y00945*
Y00946*
Y00946*
Y00947*
Y00947*
Y00948*
Y00948*
Y00949*
Y00949*
Y0095*
Y0095*
Y00951*
Y00952*
Y00952*
Y00953*
Y00953*
Y00954*
Y00954*
Y00955*
Y00955*
Y00956*
Y00956*
Y00957*
Y00958*
Y00958*
Y00959*
Y00959*
Y0096*
Y0096*
Y00961*
Y00961*
Y00962*
Y00962*
Y00963*
Y00963*
Y00964*
Y00965*
Y00965*
Y00966*
Y00966*
Y00967*
Y00967*
Y00968*
Y00968*
Y00969*
Y00969*
Y0097*
Y0097*
Y00971*
Y00972*
Y00972*
Y00973*
Y00973*
Y00974*
Y00974*
Y00975*
Y00975*
Y00976*
Y00976*
Y00977*
Y00978*
Y00978*
Y00979*
Y00979*
Y0098*
Y0098*
Y00981*
Y00981*
Y00982*
Y00982*
Y00983*
Y00983*
Y00984*
Y00985*
Y00985*
Y00986*
Y00986*
Y00987*
Y00987*
Y00988*
Y00988*
Y00989*
Y00989*
Y0099*
Y0099*
Y00991*
Y00992*
Y00992*
Y00993*
Y00993*
Y00994*
Y00994*
Y00995*
Y00995*
Y00996*
Y00996*
Y00997*
Y00998*
Y00998*
Y00999*
Y00999*
Y01*
Y01*
Y01001*
Y01001*
Y01002*
Y01002*
Y01003*
Y01003*
Y01004*
Y01005*
Y01005*
Y01006*
Y01006*
Y01007*
Y01007*
Y01008*
Y01008*
Y01009*
Y01009*
Y0101*
Y0101*
Y01011*
Y01012*
Y01012*
Y01013*
Y01013*
Y01014*
Y01014*
Y01015*
Y01015*
Y01016*
Y01016*
Y01017*
Y01018*
Y01018*
Y01019*
Y01019*
Y0102*
Y0102*
Y01021*
Y01021*
Y01022*
Y01022*
Y01023*
Y01023*
Y01024*
Y01025*
Y01025*
Y01026*
Y01026*
Y01027*
Y01027*
Y01028*
Y01028*
Y01029*
Y01029*
Y0103*
Y0103*
Y01031*
Y01032*
Y01032*
Y01033*
Y01033*
Y01034*
Y01034*
Y01035*
Y01035*
Y01036*
Y01036*
Y01037*
Y01038*
Y01038*
Y01039*
Y01039*
Y0104*
Y0104*
Y01041*
Y01041*
Y01042*
Y01042*
Y01043*
Y01043*
Y01044*
Y01045*
Y01045*
Y01046*
Y01046*
Y01047*
Y01047*
Y01048*
Y01048*
Y01049*
Y01049*
Y0105*
Y0105*
Y01051*
Y01052*
Y01052*
Y01053*
Y01053*
Y01054*
Y01054*
Y01055*
Y01055*
Y01056*
Y01056*
Y01057*
Y01058*
Y01058*
Y01059*
Y01059*
Y0106*
Y0106*
Y01061*
Y01061*
Y01062*
Y01062*
Y01063*
Y01063*
Y01064*
Y01065*
Y01065*
Y01066*
Y01066*
Y01067*
Y01067*
Y01068*
Y01068*
Y01069*
Y01069*
Y0107*
Y0107*
Y01071*
Y01072*
Y01072*
Y01073*
Y01073*
Y01074*
Y01074*
Y01075*
Y01075*
Y01076*
Y01076*
Y01077*
Y01078*
Y01078*
Y01079*
Y01079*
Y0108*
Y0108*
Y01081*
Y01081*
Y01082*
Y01082*
Y01083*
Y01083*
Y01084*
Y01085*
Y01085*
Y01086*
Y01086*
Y01087*
Y01087*
Y01088*
Y01088*
Y01089*
Y01089*
Y0109*
Y01091*
Y01091*
Y01092*
Y01092*
Y01093*
Y01093*
Y01094*
Y01094*
Y01095*
Y01095*
Y01096*
Y01096*
Y01097*
Y01098*
Y01098*
Y01099*
Y01099*
Y011*
Y011*
Y01101*
Y01101*
Y01102*
Y01102*
Y01103*
Y01103*
Y01104*
Y01105*
Y01105*
Y01106*
Y01106*
Y01107*
Y01107*
Y01108*
Y01108*
Y01109*
Y01109*
Y0111*
Y01111*
Y01111*
Y01112*
Y01112*
Y01113*
Y01113*
Y01114*
Y01114*
Y01115*
Y01115*
Y01116*
Y01116*
Y01117*
Y01118*
Y01118*
Y01119*
Y01119*
Y0112*
Y0112*
Y01121*
Y01121*
Y01122*
Y01122*
Y01123*
Y01123*
Y01124*
Y01125*
Y01125*
Y01126*
Y01126*
Y01127*
Y01127*
Y01128*
Y01128*
Y01129*
Y01129*
Y0113*
Y01131*
Y01131*
Y01132*
Y01132*
Y01133*
Y01133*
Y01134*
Y01134*
Y01135*
Y01135*
Y01136*
Y01136*
Y01137*
Y01138*
Y01138*
Y01139*
Y01139*
Y0114*
Y0114*
Y01141*
Y01141*
Y01142*
Y01142*
X05902Y01142*
X05901Y01143*
X05901Y01144*
X05901Y01144*
Y01145*
Y01145*
Y01145*
X05901Y01145*
X05901Y01145*
X05901Y01145*
X05901Y01146*
X05901Y01146*
X059Y01147*
X059Y01147*
X059Y01147*
X059Y01148*
X059Y01148*
X05899Y01148*
X05899Y01149*
X05899Y01149*
X05899Y01149*
X05899Y01149*
X05899Y01149*
X05898Y0115*
X05898Y0115*
X05897Y0115*
X05897Y0115*
X05897Y01151*
X05897Y01151*
X05896Y01151*
X05896Y01151*
X05896Y01151*
X05896Y01151*
X05895Y01151*
X05895Y01152*
X05895Y01152*
X05894Y01152*
X05894*
X05893Y01152*
X05893Y01152*
X05892Y01152*
X05892Y01152*
X05825*
X05825Y01152*
X05824Y01153*
X05824Y01153*
X05823Y01153*
X05823Y01153*
X05822Y01154*
X05822Y01154*
X05822Y01154*
X05822Y01155*
X05821Y01155*
X05821Y01156*
X05821Y01156*
Y01157*
Y01158*
Y01158*
Y01159*
Y01159*
Y0116*
Y0116*
Y01161*
Y01161*
Y01162*
Y01162*
Y01163*
Y01163*
Y01164*
Y01165*
Y01165*
Y01166*
Y01166*
Y01167*
Y01167*
Y01168*
Y01168*
Y01169*
Y01169*
Y0117*
Y01171*
Y01171*
Y01172*
Y01172*
Y01173*
Y01173*
Y01174*
Y01174*
Y01175*
Y01175*
Y01176*
Y01176*
Y01177*
X05821Y01178*
X05821Y01178*
X05822Y01179*
X05822Y01179*
X05822Y01179*
X05822Y0118*
X05823Y0118*
X05823Y0118*
X05824Y01181*
X05824Y01181*
X05825Y01181*
X05825Y01181*
X05894*
X05895Y01181*
G37*
%LNtimingcard_pcb-2*%
%LPC*%
G36*
X06387Y01041D02*
X06328D01*
X06328Y01041*
X06327Y01041*
X06327Y01041*
X06326Y01041*
X06326Y01041*
X06325*
X06325Y01041*
X06325Y0104*
X06324Y0104*
X06324Y0104*
X06324Y0104*
X06324Y0104*
X06323Y0104*
X06323Y0104*
X06323Y0104*
X06323Y01039*
X06322Y01039*
X06322Y01039*
X06322Y01038*
X06321Y01038*
X06321Y01038*
X06321Y01038*
X06321Y01037*
X0632Y01037*
X0632Y01037*
X0632Y01037*
X0632Y01037*
X0632Y01036*
X06319Y01036*
X06319Y01036*
X06319Y01036*
X06319Y01036*
X06319Y01035*
X06318Y01035*
X06318Y01035*
X06318Y01034*
X06317Y01034*
X06317Y01034*
X06317Y01034*
X06317Y01034*
X06317Y01033*
X06316Y01033*
X06316Y01033*
X06316Y01033*
X06316Y01032*
X06315Y01032*
X06315Y01032*
X06315Y01031*
X06314Y01031*
X06314Y01031*
X06314Y01031*
X06314Y01031*
X06314Y0103*
X06313Y0103*
X06313Y0103*
X06313Y0103*
X06313Y01029*
X06312Y01029*
X06312Y01029*
X06312Y01028*
X06311Y01028*
X06311Y01028*
X06311Y01028*
X06311Y01027*
X06311Y01027*
X0631Y01027*
X0631Y01027*
X0631Y01027*
X0631Y01026*
X06309Y01026*
X06309Y01026*
X06309Y01026*
X06309Y01025*
X06309Y01025*
X06309Y01025*
X06308Y01024*
Y01024*
Y01024*
Y01023*
X06308Y01023*
X06308Y01022*
X06308Y01022*
X06308Y01021*
X06308Y01021*
Y01021*
Y01021*
Y0102*
Y0102*
Y01019*
Y01019*
Y01018*
Y01018*
Y01017*
Y01016*
Y01016*
Y01015*
Y01015*
Y01014*
Y01014*
Y01013*
Y01013*
Y01012*
Y01012*
Y01011*
Y0101*
Y0101*
Y01009*
Y01009*
Y01008*
Y01008*
Y01007*
Y01007*
Y01006*
Y01006*
Y01005*
Y01005*
Y01004*
Y01003*
Y01003*
Y01002*
Y01002*
Y01001*
Y01001*
Y01*
Y01*
Y00999*
Y00999*
Y00998*
Y00998*
Y00997*
Y00996*
Y00996*
Y00995*
Y00995*
Y00994*
Y00994*
Y00993*
Y00993*
Y00992*
Y00992*
Y00991*
Y0099*
Y0099*
Y00989*
Y00989*
Y00988*
Y00988*
Y00987*
Y00987*
Y00986*
Y00986*
Y00985*
Y00985*
Y00984*
Y00983*
Y00983*
Y00982*
Y00982*
Y00981*
Y00981*
Y0098*
Y0098*
Y00979*
Y00979*
Y00978*
Y00978*
Y00977*
Y00976*
Y00976*
Y00975*
Y00975*
Y00974*
Y00974*
Y00973*
Y00973*
Y00972*
Y00972*
Y00971*
Y0097*
Y0097*
Y00969*
Y00969*
Y00968*
Y00968*
Y00967*
Y00967*
Y00966*
Y00966*
Y00965*
Y00965*
Y00964*
Y00963*
Y00963*
Y00962*
Y00962*
Y00961*
Y00961*
Y0096*
Y0096*
Y00959*
Y00959*
Y00958*
Y00958*
Y00957*
Y00956*
Y00956*
Y00955*
Y00955*
Y00954*
Y00954*
Y00953*
Y00953*
Y00952*
Y00952*
Y00951*
Y0095*
Y0095*
X06308*
X06308Y0095*
X06308Y00949*
X06308Y00949*
X06308Y00948*
Y00948*
Y00948*
Y00948*
X06309Y00947*
X06309Y00947*
X06309Y00947*
X06309Y00946*
X06309Y00946*
X06309Y00946*
X0631Y00945*
X0631Y00945*
X0631Y00945*
X0631Y00945*
X06311Y00944*
X06311Y00944*
X06311Y00944*
X06311Y00944*
X06312Y00943*
X06312Y00943*
X06312Y00943*
X06312Y00943*
X06313Y00943*
X06313Y00942*
X06313Y00942*
X06313Y00942*
X06314Y00941*
X06314Y00941*
X06314Y00941*
X06314Y00941*
X06315Y0094*
X06315Y0094*
X06315Y0094*
X06316Y0094*
X06316Y00939*
X06316Y00939*
X06316Y00939*
X06317Y00938*
X06317Y00938*
X06317Y00938*
X06317Y00938*
X06318Y00937*
X06318Y00937*
X06318Y00937*
X06318Y00937*
X06319Y00937*
X06319Y00936*
X06319Y00936*
X06319Y00936*
X06319Y00936*
X0632Y00935*
X0632Y00935*
X0632Y00935*
X0632Y00935*
X06321Y00934*
X06321Y00934*
X06321Y00934*
X06321Y00934*
X06322Y00933*
X06322Y00933*
X06322Y00933*
X06323Y00932*
X06323Y00932*
X06323Y00932*
X06323Y00932*
X06324Y00932*
X06324*
X06324*
X06324Y00932*
X06325Y00932*
X06325Y00931*
X06326Y00931*
X06326*
X0639*
X0639Y00931*
Y00932*
Y00932*
Y00933*
Y00933*
Y00934*
Y00934*
Y00935*
Y00935*
Y00936*
Y00936*
Y00937*
Y00938*
Y00938*
Y00939*
Y00939*
Y0094*
Y0094*
Y00941*
Y00941*
Y00942*
Y00942*
Y00943*
Y00943*
Y00944*
Y00945*
Y00945*
Y00946*
Y00946*
Y00947*
Y00947*
Y00948*
Y00948*
Y00949*
Y00949*
Y0095*
Y0095*
Y00951*
X0639Y00951*
X0639Y00951*
X06334*
X06334Y00951*
X06333Y00951*
X06333Y00951*
X06332Y00951*
X06332Y00952*
X06331Y00952*
X06331Y00952*
X06331Y00952*
X06331Y00953*
X0633Y00953*
X0633Y00953*
X0633Y00954*
X0633Y00954*
X0633Y00955*
X0633Y00955*
Y00956*
Y00956*
Y00957*
Y00958*
Y00958*
Y00959*
Y00959*
Y0096*
Y0096*
Y00961*
Y00961*
Y00962*
Y00962*
Y00963*
Y00963*
Y00964*
Y00965*
Y00965*
Y00966*
Y00966*
Y00967*
Y00967*
Y00968*
Y00968*
Y00969*
Y00969*
Y0097*
Y0097*
Y00971*
Y00972*
Y00972*
Y00973*
Y00973*
Y00974*
X0633Y00974*
X0633Y00975*
X0633Y00975*
X0633Y00976*
X0633Y00976*
X06331Y00977*
X06331Y00977*
X06331Y00977*
X06332Y00977*
X06332Y00978*
X06333Y00978*
X06333Y00978*
X06334Y00978*
X06334Y00978*
X06381*
Y00979*
Y00979*
Y0098*
Y0098*
Y00981*
Y00981*
Y00982*
Y00982*
Y00983*
Y00983*
Y00984*
Y00985*
Y00985*
Y00986*
Y00986*
Y00987*
Y00987*
Y00988*
Y00988*
Y00989*
Y00989*
Y0099*
Y0099*
Y00991*
Y00992*
Y00992*
Y00993*
Y00993*
Y00994*
X06334*
X06334Y00994*
X06333Y00994*
X06333Y00994*
X06332Y00994*
X06332Y00994*
X06331Y00995*
X06331Y00995*
X06331Y00995*
X0633Y00996*
X0633Y00996*
X0633Y00997*
X0633Y00997*
X0633Y00998*
X0633Y00998*
Y00999*
Y00999*
Y01*
Y01*
Y01001*
Y01001*
Y01002*
Y01002*
Y01003*
Y01003*
Y01004*
Y01005*
Y01005*
Y01006*
Y01006*
Y01007*
Y01007*
Y01008*
Y01008*
Y01009*
Y01009*
Y0101*
Y0101*
Y01011*
Y01012*
Y01012*
Y01013*
Y01013*
Y01014*
Y01014*
Y01015*
Y01015*
Y01016*
Y01016*
Y01017*
X0633Y01017*
X0633Y01018*
X0633Y01019*
X0633Y01019*
X0633Y01019*
X06331Y0102*
X06331Y0102*
X06331Y0102*
X06332Y01021*
X06332Y01021*
X06333Y01021*
X06333Y01021*
X06334Y01021*
X06334Y01022*
X0639*
Y01022*
Y01022*
Y01023*
Y01023*
Y01024*
Y01025*
Y01025*
Y01026*
Y01026*
Y01027*
Y01027*
Y01028*
Y01028*
Y01029*
Y01029*
Y0103*
Y0103*
Y01031*
Y01032*
Y01032*
Y01033*
Y01033*
Y01034*
Y01034*
Y01035*
Y01035*
Y01036*
Y01036*
Y01037*
Y01038*
Y01038*
Y01039*
Y01039*
Y0104*
Y0104*
Y0104*
Y0104*
X0639Y01041*
X0639Y01041*
X06389*
X06389Y01041*
X06388Y01041*
X06388Y01041*
X06387Y01041*
X06387Y01041*
G37*
G36*
X06248D02*
X06172D01*
Y01041*
X06171Y01041*
X06171Y01041*
Y0104*
Y0104*
Y01039*
Y01039*
Y01038*
Y01038*
Y01037*
Y01036*
Y01036*
Y01035*
Y01035*
Y01034*
Y01034*
Y01033*
Y01033*
Y01032*
Y01032*
Y01031*
Y0103*
Y0103*
Y01029*
Y01029*
Y01028*
Y01028*
Y01027*
Y01027*
Y01026*
Y01026*
Y01025*
Y01025*
Y01024*
Y01023*
Y01023*
Y01022*
Y01022*
Y01021*
Y01021*
Y0102*
Y0102*
Y01019*
Y01019*
Y01018*
Y01018*
Y01017*
Y01016*
Y01016*
Y01015*
Y01015*
Y01014*
Y01014*
Y01013*
Y01013*
Y01012*
Y01012*
Y01011*
Y0101*
Y0101*
Y01009*
Y01009*
Y01008*
Y01008*
Y01007*
Y01007*
Y01006*
Y01006*
Y01005*
Y01005*
Y01004*
Y01003*
Y01003*
Y01002*
Y01002*
Y01001*
Y01001*
Y01*
Y01*
Y00999*
Y00999*
Y00998*
Y00998*
Y00997*
Y00996*
Y00996*
Y00995*
Y00995*
Y00994*
Y00994*
Y00993*
Y00993*
Y00992*
Y00992*
Y00991*
Y0099*
Y0099*
Y00989*
Y00989*
Y00988*
Y00988*
Y00987*
Y00987*
Y00986*
Y00986*
Y00985*
Y00985*
Y00984*
Y00983*
Y00983*
Y00982*
Y00982*
Y00981*
Y00981*
Y0098*
Y0098*
Y00979*
Y00979*
Y00978*
Y00978*
Y00977*
Y00976*
Y00976*
Y00975*
Y00975*
Y00974*
Y00974*
Y00973*
Y00973*
Y00972*
Y00972*
Y00971*
Y0097*
Y0097*
Y00969*
Y00969*
Y00968*
Y00968*
Y00967*
Y00967*
Y00966*
Y00966*
Y00965*
Y00965*
Y00964*
Y00963*
Y00963*
Y00962*
Y00962*
Y00961*
Y00961*
Y0096*
Y0096*
Y00959*
Y00959*
Y00958*
Y00958*
Y00957*
Y00956*
Y00956*
Y00955*
Y00955*
Y00954*
Y00954*
Y00953*
Y00953*
Y00952*
Y00952*
Y00951*
Y0095*
Y0095*
Y00949*
Y00949*
Y00948*
Y00948*
Y00947*
Y00947*
Y00946*
Y00946*
Y00945*
Y00945*
Y00944*
Y00943*
Y00943*
Y00942*
Y00942*
Y00941*
Y00941*
Y0094*
Y0094*
Y00939*
Y00939*
Y00938*
Y00938*
Y00937*
Y00936*
Y00936*
Y00935*
Y00935*
Y00934*
Y00934*
Y00933*
Y00933*
Y00932*
Y00932*
Y00931*
X06193*
X06193Y00931*
Y00932*
Y00932*
Y00933*
Y00933*
Y00934*
Y00934*
Y00935*
Y00935*
Y00936*
Y00936*
Y00937*
Y00938*
Y00938*
Y00939*
Y00939*
Y0094*
Y0094*
Y00941*
Y00941*
Y00942*
Y00942*
Y00943*
Y00943*
Y00944*
Y00945*
Y00945*
Y00946*
Y00946*
Y00947*
Y00947*
Y00948*
Y00948*
Y00949*
Y00949*
Y0095*
Y0095*
Y00951*
Y00952*
Y00952*
Y00953*
Y00953*
Y00954*
Y00954*
Y00955*
Y00955*
Y00956*
Y00956*
Y00957*
Y00958*
Y00958*
Y00959*
Y00959*
Y0096*
Y0096*
Y00961*
Y00961*
Y00962*
Y00962*
Y00963*
Y00963*
Y00964*
Y00965*
Y00965*
Y00966*
Y00966*
Y00967*
Y00967*
Y00968*
Y00968*
Y00969*
Y00969*
Y0097*
Y0097*
Y00971*
Y00972*
Y00972*
Y00973*
Y00973*
Y00974*
Y00974*
Y00975*
Y00975*
Y00976*
Y00976*
Y00977*
Y00978*
Y00978*
Y00979*
Y00979*
Y0098*
Y0098*
Y00981*
Y00981*
Y00982*
Y00982*
Y00983*
Y00983*
Y00984*
Y00985*
Y00985*
Y00986*
Y00986*
Y00987*
Y00987*
Y00988*
Y00988*
Y00989*
Y00989*
Y0099*
Y0099*
Y00991*
Y00992*
Y00992*
Y00993*
Y00993*
Y00994*
Y00994*
Y00995*
Y00995*
Y00996*
Y00996*
Y00997*
Y00998*
Y00998*
Y00999*
Y00999*
Y01*
Y01*
Y01001*
Y01001*
Y01002*
Y01002*
Y01003*
Y01003*
Y01004*
Y01005*
Y01005*
Y01006*
Y01006*
Y01007*
Y01007*
Y01008*
Y01008*
Y01009*
Y01009*
Y0101*
Y0101*
Y01011*
Y01012*
Y01012*
Y01013*
Y01013*
Y01014*
Y01014*
Y01015*
Y01015*
Y01016*
X06193Y01016*
X06193Y01017*
X06193Y01017*
X06193Y01018*
X06194Y01018*
X06194Y01019*
X06194Y01019*
X06195Y01019*
X06195Y0102*
X06196Y0102*
X06196Y0102*
X06197Y0102*
X06215*
X06216Y0102*
X06216Y0102*
X06217Y0102*
X06217Y01019*
X06218Y01019*
X06218Y01019*
X06218Y01018*
X06219Y01018*
X06219Y01017*
X06219Y01017*
X06219Y01016*
X06219Y01016*
Y01015*
Y01015*
Y01014*
Y01014*
Y01013*
Y01013*
Y01012*
Y01012*
Y01011*
Y0101*
Y0101*
Y01009*
Y01009*
Y01008*
Y01008*
Y01007*
Y01007*
Y01006*
Y01006*
Y01005*
Y01005*
Y01004*
Y01003*
Y01003*
Y01002*
Y01002*
Y01001*
Y01001*
Y01*
Y01*
Y00999*
Y00999*
Y00998*
Y00998*
Y00997*
Y00996*
Y00996*
Y00995*
Y00995*
Y00994*
Y00994*
Y00993*
Y00993*
Y00992*
Y00992*
Y00991*
Y0099*
Y0099*
Y00989*
Y00989*
Y00988*
Y00988*
Y00987*
Y00987*
Y00986*
Y00986*
Y00985*
Y00985*
Y00984*
Y00983*
Y00983*
Y00982*
Y00982*
Y00981*
Y00981*
Y0098*
Y0098*
Y00979*
Y00979*
Y00978*
Y00978*
Y00977*
Y00976*
Y00976*
Y00975*
Y00975*
Y00974*
Y00974*
Y00973*
Y00973*
Y00972*
Y00972*
Y00971*
Y0097*
Y0097*
Y00969*
Y00969*
Y00968*
Y00968*
Y00967*
Y00967*
Y00966*
Y00966*
Y00965*
Y00965*
Y00964*
Y00963*
Y00963*
Y00962*
Y00962*
Y00961*
Y00961*
Y0096*
Y0096*
Y00959*
Y00959*
Y00958*
Y00958*
Y00957*
Y00956*
Y00956*
Y00955*
Y00955*
Y00954*
Y00954*
Y00953*
Y00953*
Y00952*
Y00952*
Y00951*
Y0095*
Y0095*
Y00949*
Y00949*
Y00948*
Y00948*
Y00947*
Y00947*
Y00946*
Y00946*
Y00945*
Y00945*
Y00944*
Y00943*
Y00943*
Y00942*
Y00942*
Y00941*
Y00941*
Y0094*
Y0094*
Y00939*
Y00939*
Y00938*
Y00938*
Y00937*
Y00936*
Y00936*
Y00935*
Y00935*
Y00934*
Y00934*
Y00933*
Y00933*
Y00932*
Y00932*
Y00931*
X06219*
X06219Y00931*
X06219Y00931*
X06219*
X06239*
Y00932*
Y00932*
Y00933*
Y00933*
Y00934*
Y00934*
Y00935*
Y00935*
Y00936*
Y00936*
Y00937*
Y00938*
Y00938*
Y00939*
Y00939*
Y0094*
Y0094*
Y00941*
Y00941*
Y00942*
Y00942*
Y00943*
Y00943*
Y00944*
Y00945*
Y00945*
Y00946*
Y00946*
Y00947*
Y00947*
Y00948*
Y00948*
Y00949*
Y00949*
Y0095*
Y0095*
Y00951*
Y00952*
Y00952*
Y00953*
Y00953*
Y00954*
Y00954*
Y00955*
Y00955*
Y00956*
Y00956*
Y00957*
Y00958*
Y00958*
Y00959*
Y00959*
Y0096*
Y0096*
Y00961*
Y00961*
Y00962*
Y00962*
Y00963*
Y00963*
Y00964*
Y00965*
Y00965*
Y00966*
Y00966*
Y00967*
Y00967*
Y00968*
Y00968*
Y00969*
Y00969*
Y0097*
Y0097*
Y00971*
Y00972*
Y00972*
Y00973*
Y00973*
Y00974*
Y00974*
Y00975*
Y00975*
Y00976*
Y00976*
Y00977*
Y00978*
Y00978*
Y00979*
Y00979*
Y0098*
Y0098*
Y00981*
Y00981*
Y00982*
Y00982*
Y00983*
Y00983*
Y00984*
Y00985*
Y00985*
Y00986*
Y00986*
Y00987*
Y00987*
Y00988*
Y00988*
Y00989*
Y00989*
Y0099*
Y0099*
Y00991*
Y00992*
Y00992*
Y00993*
Y00993*
Y00994*
Y00994*
Y00995*
Y00995*
Y00996*
Y00996*
Y00997*
Y00998*
Y00998*
Y00999*
Y00999*
Y01*
Y01*
Y01001*
Y01001*
Y01002*
Y01002*
Y01003*
Y01003*
Y01004*
Y01005*
Y01005*
Y01006*
Y01006*
Y01007*
Y01007*
Y01008*
Y01008*
Y01009*
Y01009*
Y0101*
Y0101*
Y01011*
Y01012*
Y01012*
Y01013*
Y01013*
Y01014*
Y01014*
Y01015*
Y01015*
Y01016*
X06239Y01016*
X06239Y01017*
X06239Y01017*
X06239Y01018*
X0624Y01018*
X0624Y01019*
X0624Y01019*
X06241Y01019*
X06241Y0102*
X06242Y0102*
X06242Y0102*
X06243Y0102*
X06248*
X06248*
X06248Y0102*
Y0102*
Y01021*
Y01021*
Y01022*
Y01022*
Y01023*
Y01023*
Y01024*
Y01025*
Y01025*
Y01026*
Y01026*
Y01027*
Y01027*
Y01028*
Y01028*
Y01029*
Y01029*
Y0103*
Y0103*
Y01031*
Y01032*
Y01032*
Y01033*
Y01033*
Y01034*
Y01034*
Y01035*
Y01035*
Y01036*
Y01036*
Y01037*
Y01038*
Y01038*
Y01039*
Y01039*
Y0104*
Y0104*
Y01041*
Y01041*
G37*
G36*
X06149D02*
X06128D01*
Y01041*
X06128Y01041*
X06128Y0104*
X06128Y0104*
Y0104*
Y0104*
Y0104*
Y01039*
Y01039*
Y01038*
Y01038*
Y01037*
Y01036*
Y01036*
Y01035*
Y01035*
Y01034*
Y01034*
Y01033*
Y01033*
Y01032*
Y01032*
Y01031*
Y0103*
Y0103*
Y01029*
Y01029*
Y01028*
Y01028*
Y01027*
Y01027*
Y01026*
Y01026*
Y01025*
Y01025*
Y01024*
Y01023*
Y01023*
Y01022*
Y01022*
Y01021*
Y01021*
Y0102*
Y0102*
Y01019*
Y01019*
Y01018*
Y01018*
Y01017*
Y01016*
Y01016*
Y01015*
Y01015*
Y01014*
Y01014*
Y01013*
Y01013*
Y01012*
Y01012*
Y01011*
Y0101*
Y0101*
Y01009*
Y01009*
Y01008*
Y01008*
Y01007*
Y01007*
Y01006*
Y01006*
Y01005*
Y01005*
Y01004*
Y01003*
Y01003*
Y01002*
Y01002*
Y01001*
Y01001*
Y01*
Y01*
Y00999*
Y00999*
Y00998*
Y00998*
Y00997*
Y00996*
Y00996*
Y00995*
Y00995*
Y00994*
Y00994*
Y00993*
Y00993*
Y00992*
Y00992*
Y00991*
Y0099*
Y0099*
Y00989*
Y00989*
Y00988*
Y00988*
Y00987*
Y00987*
Y00986*
Y00986*
Y00985*
Y00985*
Y00984*
Y00983*
Y00983*
Y00982*
Y00982*
Y00981*
Y00981*
Y0098*
Y0098*
Y00979*
Y00979*
Y00978*
Y00978*
Y00977*
Y00976*
Y00976*
Y00975*
Y00975*
Y00974*
Y00974*
Y00973*
Y00973*
Y00972*
Y00972*
Y00971*
Y0097*
Y0097*
Y00969*
Y00969*
Y00968*
Y00968*
Y00967*
Y00967*
Y00966*
Y00966*
Y00965*
Y00965*
Y00964*
Y00963*
Y00963*
Y00962*
Y00962*
Y00961*
Y00961*
Y0096*
Y0096*
Y00959*
Y00959*
Y00958*
Y00958*
Y00957*
Y00956*
Y00956*
Y00955*
Y00955*
Y00954*
Y00954*
Y00953*
Y00953*
Y00952*
Y00952*
Y00951*
Y0095*
Y0095*
Y00949*
Y00949*
Y00948*
Y00948*
Y00947*
Y00947*
Y00946*
Y00946*
Y00945*
Y00945*
Y00944*
Y00943*
Y00943*
Y00942*
Y00942*
Y00941*
Y00941*
Y0094*
Y0094*
Y00939*
Y00939*
Y00938*
Y00938*
Y00937*
Y00936*
Y00936*
Y00935*
Y00935*
Y00934*
Y00934*
Y00933*
Y00933*
Y00932*
Y00932*
Y00931*
X06128Y00931*
X06149*
Y00932*
Y00932*
Y00933*
Y00933*
Y00934*
Y00934*
Y00935*
Y00935*
Y00936*
Y00936*
Y00937*
Y00938*
Y00938*
Y00939*
Y00939*
Y0094*
Y0094*
Y00941*
Y00941*
Y00942*
Y00942*
Y00943*
Y00943*
Y00944*
Y00945*
Y00945*
Y00946*
Y00946*
Y00947*
Y00947*
Y00948*
Y00948*
Y00949*
Y00949*
Y0095*
Y0095*
Y00951*
Y00952*
Y00952*
Y00953*
Y00953*
Y00954*
Y00954*
Y00955*
Y00955*
Y00956*
Y00956*
Y00957*
Y00958*
Y00958*
Y00959*
Y00959*
Y0096*
Y0096*
Y00961*
Y00961*
Y00962*
Y00962*
Y00963*
Y00963*
Y00964*
Y00965*
Y00965*
Y00966*
Y00966*
Y00967*
Y00967*
Y00968*
Y00968*
Y00969*
Y00969*
Y0097*
Y0097*
Y00971*
Y00972*
Y00972*
Y00973*
Y00973*
Y00974*
Y00974*
Y00975*
Y00975*
Y00976*
Y00976*
Y00977*
Y00978*
Y00978*
Y00979*
Y00979*
Y0098*
Y0098*
Y00981*
Y00981*
Y00982*
Y00982*
Y00983*
Y00983*
Y00984*
Y00985*
Y00985*
Y00986*
Y00986*
Y00987*
Y00987*
Y00988*
Y00988*
Y00989*
Y00989*
Y0099*
Y0099*
Y00991*
Y00992*
Y00992*
Y00993*
Y00993*
Y00994*
Y00994*
Y00995*
Y00995*
Y00996*
Y00996*
Y00997*
Y00998*
Y00998*
Y00999*
Y00999*
Y01*
Y01*
Y01001*
Y01001*
Y01002*
Y01002*
Y01003*
Y01003*
Y01004*
Y01005*
Y01005*
Y01006*
Y01006*
Y01007*
Y01007*
Y01008*
Y01008*
Y01009*
Y01009*
Y0101*
Y0101*
Y01011*
Y01012*
Y01012*
Y01013*
Y01013*
Y01014*
Y01014*
Y01015*
Y01015*
Y01016*
Y01016*
Y01017*
Y01018*
Y01018*
Y01019*
Y01019*
Y0102*
Y0102*
Y01021*
Y01021*
Y01022*
Y01022*
Y01023*
Y01023*
Y01024*
Y01025*
Y01025*
Y01026*
Y01026*
Y01027*
Y01027*
Y01028*
Y01028*
Y01029*
Y01029*
Y0103*
Y0103*
Y01031*
Y01032*
Y01032*
Y01033*
Y01033*
Y01034*
Y01034*
Y01035*
Y01035*
Y01036*
Y01036*
Y01037*
Y01038*
Y01038*
Y01039*
Y01039*
Y0104*
Y0104*
Y01041*
Y01041*
X06149Y01041*
X06149Y01041*
G37*
G36*
X06111D02*
X06032D01*
Y01041*
X06031Y01041*
X06031Y01041*
Y0104*
Y0104*
Y01039*
Y01039*
Y01038*
Y01038*
Y01037*
Y01036*
Y01036*
Y01035*
Y01035*
Y01034*
Y01034*
Y01033*
Y01033*
Y01032*
Y01032*
Y01031*
Y0103*
Y0103*
Y01029*
Y01029*
Y01028*
Y01028*
Y01027*
Y01027*
Y01026*
Y01026*
Y01025*
Y01025*
Y01024*
Y01023*
Y01023*
Y01022*
Y01022*
Y01021*
Y01021*
Y0102*
X06031Y0102*
X06031Y0102*
X06032Y0102*
X06056*
X06056Y0102*
X06057Y0102*
X06057Y0102*
X06058Y01019*
X06058Y01019*
X06058Y01019*
X06059Y01018*
X06059Y01018*
X06059Y01018*
X06059Y01018*
X0606Y01018*
X0606Y01017*
X0606Y01017*
X0606Y01016*
X06061Y01016*
X06061Y01016*
X06061Y01015*
X06061Y01015*
X06061Y01014*
X06061Y01014*
Y01013*
Y01013*
Y01012*
Y01012*
Y01011*
Y0101*
Y0101*
Y01009*
Y01009*
Y01008*
Y01008*
Y01007*
Y01007*
Y01006*
Y01006*
Y01005*
Y01005*
Y01004*
Y01003*
Y01003*
Y01002*
Y01002*
Y01001*
Y01001*
Y01*
Y01*
Y00999*
Y00999*
Y00998*
Y00998*
Y00997*
Y00996*
Y00996*
Y00995*
Y00995*
Y00994*
Y00994*
Y00993*
Y00993*
Y00992*
Y00992*
Y00991*
Y0099*
Y0099*
Y00989*
Y00989*
Y00988*
Y00988*
Y00987*
Y00987*
Y00986*
Y00986*
Y00985*
Y00985*
Y00984*
Y00983*
Y00983*
Y00982*
Y00982*
Y00981*
Y00981*
Y0098*
Y0098*
Y00979*
Y00979*
Y00978*
Y00978*
Y00977*
Y00976*
Y00976*
Y00975*
Y00975*
Y00974*
Y00974*
Y00973*
Y00973*
Y00972*
Y00972*
Y00971*
Y0097*
Y0097*
Y00969*
Y00969*
Y00968*
Y00968*
Y00967*
Y00967*
Y00966*
Y00966*
Y00965*
Y00965*
Y00964*
Y00963*
Y00963*
Y00962*
Y00962*
Y00961*
Y00961*
Y0096*
Y0096*
Y00959*
Y00959*
Y00958*
Y00958*
Y00957*
Y00956*
Y00956*
Y00955*
Y00955*
Y00954*
Y00954*
Y00953*
Y00953*
Y00952*
Y00952*
Y00951*
Y0095*
Y0095*
Y00949*
Y00949*
Y00948*
Y00948*
Y00947*
Y00947*
Y00946*
Y00946*
Y00945*
Y00945*
Y00944*
Y00943*
Y00943*
Y00942*
Y00942*
Y00941*
Y00941*
Y0094*
Y0094*
Y00939*
Y00939*
Y00938*
Y00938*
Y00937*
Y00936*
Y00936*
Y00935*
Y00935*
Y00934*
Y00934*
Y00933*
Y00933*
Y00932*
Y00932*
Y00931*
X06083*
X06083Y00931*
X06083Y00932*
Y00932*
Y00933*
Y00933*
Y00934*
Y00934*
Y00935*
Y00935*
Y00936*
Y00936*
Y00937*
Y00938*
Y00938*
Y00939*
Y00939*
Y0094*
Y0094*
Y00941*
Y00941*
Y00942*
Y00942*
Y00943*
Y00943*
Y00944*
Y00945*
Y00945*
Y00946*
Y00946*
Y00947*
Y00947*
Y00948*
Y00948*
Y00949*
Y00949*
Y0095*
Y0095*
Y00951*
Y00952*
Y00952*
Y00953*
Y00953*
Y00954*
Y00954*
Y00955*
Y00955*
Y00956*
Y00956*
Y00957*
Y00958*
Y00958*
Y00959*
Y00959*
Y0096*
Y0096*
Y00961*
Y00961*
Y00962*
Y00962*
Y00963*
Y00963*
Y00964*
Y00965*
Y00965*
Y00966*
Y00966*
Y00967*
Y00967*
Y00968*
Y00968*
Y00969*
Y00969*
Y0097*
Y0097*
Y00971*
Y00972*
Y00972*
Y00973*
Y00973*
Y00974*
Y00974*
Y00975*
Y00975*
Y00976*
Y00976*
Y00977*
Y00978*
Y00978*
Y00979*
Y00979*
Y0098*
Y0098*
Y00981*
Y00981*
Y00982*
Y00982*
Y00983*
Y00983*
Y00984*
Y00985*
Y00985*
Y00986*
Y00986*
Y00987*
Y00987*
Y00988*
Y00988*
Y00989*
Y00989*
Y0099*
Y0099*
Y00991*
Y00992*
Y00992*
Y00993*
Y00993*
Y00994*
Y00994*
Y00995*
Y00995*
Y00996*
Y00996*
Y00997*
Y00998*
Y00998*
Y00999*
Y00999*
Y01*
Y01*
Y01001*
Y01001*
Y01002*
Y01002*
Y01003*
Y01003*
Y01004*
Y01005*
Y01005*
Y01006*
Y01006*
Y01007*
Y01007*
Y01008*
Y01008*
Y01009*
Y01009*
Y0101*
Y0101*
Y01011*
Y01012*
Y01012*
Y01013*
Y01013*
Y01014*
Y01014*
Y01015*
X06083Y01015*
X06083Y01016*
X06083Y01016*
X06084Y01017*
X06084Y01017*
X06084Y01018*
X06084Y01018*
X06085Y01018*
X06085Y01018*
X06085Y01019*
X06086Y01019*
X06086Y01019*
X06087Y0102*
X06087Y0102*
X06088Y0102*
X06088Y0102*
X06112*
X06112Y0102*
X06113Y0102*
X06113Y01021*
X06113Y01021*
Y01021*
Y01022*
Y01022*
Y01023*
Y01023*
Y01024*
Y01025*
Y01025*
Y01026*
Y01026*
Y01027*
Y01027*
Y01028*
Y01028*
Y01029*
Y01029*
Y0103*
Y0103*
Y01031*
Y01032*
Y01032*
Y01033*
Y01033*
Y01034*
Y01034*
Y01035*
Y01035*
Y01036*
Y01036*
Y01037*
Y01038*
Y01038*
Y01039*
Y01039*
Y0104*
Y0104*
Y0104*
X06113Y0104*
X06113Y01041*
X06113Y01041*
X06112Y01041*
X06112Y01041*
X06111Y01041*
X06111Y01041*
Y01041*
G37*
G36*
X0621Y00913D02*
X0615D01*
X0615*
X06149Y00913*
X06149Y00913*
X06148Y00913*
X06148*
X06148Y00913*
X06147Y00913*
X06147Y00913*
X06146Y00912*
X06146*
X06146Y00912*
X06146Y00912*
X06146Y00912*
X06146Y00912*
X06145Y00912*
X06145Y00911*
X06145Y00911*
X06144Y00911*
X06144Y00911*
X06144Y0091*
X06144Y0091*
X06143Y0091*
X06143Y0091*
X06143Y00909*
X06143Y00909*
X06142Y00909*
X06142Y00908*
X06142Y00908*
X06141Y00908*
X06141Y00908*
X06141Y00908*
X06141Y00907*
X06141Y00907*
X0614Y00907*
X0614Y00907*
X0614Y00906*
X0614Y00906*
X06139Y00906*
X06139Y00905*
X06139Y00905*
X06139Y00905*
X06138Y00905*
X06138Y00905*
X06138Y00904*
X06138Y00904*
X06137Y00904*
X06137Y00904*
X06137Y00903*
X06137Y00903*
X06136Y00903*
X06136Y00903*
X06136Y00902*
X06135Y00902*
X06135Y00902*
X06135Y00901*
X06135Y00901*
X06134Y00901*
X06134Y00901*
X06134Y009*
X06134Y009*
X06133Y009*
X06133Y009*
X06133Y00899*
X06133Y00899*
X06133Y00899*
X06133Y00899*
X06132Y00899*
X06132Y00898*
X06132Y00898*
X06132Y00898*
X06132Y00898*
X06132Y00898*
X06132*
Y00897*
X06132Y00897*
X06131Y00896*
X06131Y00896*
X06131Y00895*
X06131*
Y00895*
Y00895*
Y00894*
Y00894*
Y00893*
Y00893*
Y00892*
Y00892*
Y00891*
Y0089*
Y0089*
Y00889*
Y00889*
Y00888*
Y00888*
Y00887*
Y00887*
Y00886*
Y00886*
Y00885*
Y00885*
Y00884*
Y00883*
Y00883*
Y00882*
Y00882*
Y00881*
Y00881*
Y0088*
Y0088*
Y00879*
Y00879*
Y00878*
Y00877*
Y00877*
Y00876*
Y00876*
Y00875*
Y00875*
Y00874*
Y00874*
Y00873*
Y00873*
Y00872*
Y00872*
Y00871*
Y0087*
Y0087*
Y00869*
Y00869*
Y00868*
Y00868*
Y00867*
Y00867*
Y00866*
Y00866*
Y00865*
Y00865*
Y00864*
Y00863*
Y00863*
Y00862*
Y00862*
Y00861*
Y00861*
Y0086*
Y0086*
Y00859*
Y00859*
Y00858*
Y00857*
Y00857*
Y00856*
Y00856*
Y00855*
Y00855*
Y00854*
Y00854*
Y00853*
Y00853*
Y00852*
Y00852*
Y00851*
Y0085*
Y0085*
Y00849*
Y00849*
Y00848*
Y00848*
Y00847*
Y00847*
Y00846*
Y00846*
Y00845*
Y00845*
Y00844*
Y00843*
Y00843*
Y00842*
Y00842*
Y00841*
Y00841*
Y0084*
Y0084*
Y00839*
Y00839*
Y00838*
Y00837*
Y00837*
Y00836*
Y00836*
Y00835*
Y00835*
Y00834*
Y00834*
Y00833*
Y00833*
Y00832*
Y00832*
Y00831*
Y0083*
Y0083*
Y00829*
Y00829*
Y00828*
Y00828*
Y00827*
Y00827*
Y00826*
Y00826*
Y00825*
Y00825*
Y00824*
Y00823*
Y00823*
Y00822*
Y00822*
Y00821*
Y00821*
X06131*
X06131Y00821*
X06131Y0082*
X06132Y0082*
Y0082*
X06132Y00819*
X06132Y00819*
X06132Y00819*
X06132Y00819*
X06132Y00818*
X06133Y00818*
X06133Y00818*
X06133Y00818*
X06133Y00817*
X06134Y00817*
X06134Y00817*
X06134Y00817*
X06134Y00816*
X06134Y00816*
X06135Y00816*
X06135Y00816*
X06135Y00816*
X06135Y00815*
X06135Y00815*
X06136Y00815*
X06136Y00815*
X06136Y00814*
X06136Y00814*
X06137Y00814*
X06137Y00814*
X06137Y00814*
X06137Y00813*
X06137Y00813*
X06138Y00813*
X06138Y00813*
X06138Y00812*
X06138Y00812*
X06139Y00812*
X06139Y00812*
X06139Y00811*
X0614Y00811*
X0614Y00811*
X0614Y00811*
X0614Y0081*
X0614Y0081*
X06141Y0081*
X06141Y0081*
Y0081*
X06141Y0081*
X06141Y0081*
X06141Y00809*
X06142Y00809*
X06142Y00809*
X06142Y00809*
X06142Y00808*
X06143Y00808*
X06143Y00808*
X06143Y00808*
X06143Y00807*
X06143Y00807*
X06144Y00807*
X06144Y00807*
X06144Y00807*
X06144Y00806*
X06145Y00806*
X06145Y00806*
X06145Y00805*
X06146Y00805*
X06146Y00805*
X06146Y00805*
X06146Y00804*
X06146Y00804*
X06147Y00804*
X06147Y00804*
X06147*
X06147Y00804*
X06148Y00804*
X06148Y00804*
X06213*
Y00804*
Y00805*
Y00805*
Y00806*
Y00806*
Y00807*
Y00807*
Y00808*
Y00808*
Y00809*
Y00809*
Y0081*
Y0081*
Y00811*
Y00812*
Y00812*
Y00813*
Y00813*
Y00814*
Y00814*
Y00815*
Y00815*
Y00816*
Y00816*
Y00817*
Y00817*
Y00818*
Y00819*
Y00819*
Y0082*
Y0082*
Y00821*
Y00821*
Y00822*
Y00822*
Y00823*
Y00823*
Y00824*
Y00824*
X06213Y00824*
X06213Y00824*
X06158*
X06158Y00824*
X06157Y00824*
X06157Y00825*
X06156Y00825*
X06156Y00825*
X06156Y00825*
X06155Y00825*
X06155Y00826*
X06154Y00826*
X06154Y00826*
X06154Y00827*
X06154Y00827*
X06154Y00827*
X06153Y00828*
X06153Y00828*
X06153Y00828*
X06153Y00829*
X06153Y00829*
X06153Y0083*
Y0083*
Y00831*
Y00832*
Y00832*
Y00833*
Y00833*
Y00834*
Y00834*
Y00835*
Y00835*
Y00836*
Y00836*
Y00837*
Y00837*
Y00838*
Y00839*
Y00839*
Y0084*
Y0084*
Y00841*
Y00841*
Y00842*
Y00842*
Y00843*
Y00843*
Y00844*
Y00845*
Y00845*
Y00846*
Y00846*
Y00847*
Y00847*
Y00848*
Y00848*
Y00849*
Y00849*
Y0085*
Y0085*
Y00851*
Y00852*
Y00852*
Y00853*
Y00853*
Y00854*
Y00854*
Y00855*
Y00855*
Y00856*
Y00856*
Y00857*
Y00857*
Y00858*
Y00859*
Y00859*
Y0086*
Y0086*
Y00861*
Y00861*
Y00862*
Y00862*
Y00863*
Y00863*
Y00864*
Y00865*
Y00865*
Y00866*
Y00866*
Y00867*
Y00867*
Y00868*
Y00868*
Y00869*
Y00869*
Y0087*
Y0087*
Y00871*
Y00872*
Y00872*
Y00873*
Y00873*
Y00874*
Y00874*
Y00875*
Y00875*
Y00876*
Y00876*
Y00877*
Y00877*
Y00878*
Y00879*
Y00879*
Y0088*
Y0088*
Y00881*
Y00881*
Y00882*
Y00882*
Y00883*
Y00883*
Y00884*
Y00885*
Y00885*
Y00886*
Y00886*
Y00887*
Y00887*
X06153Y00888*
X06153Y00888*
X06153Y00889*
X06153Y00889*
X06154Y0089*
X06154Y0089*
X06154Y0089*
X06154Y0089*
X06154Y00891*
X06155Y00891*
X06155Y00891*
X06155Y00891*
X06156Y00892*
X06156Y00892*
X06157Y00892*
X06157Y00892*
X06158Y00892*
X06209*
X06209Y00892*
X0621Y00893*
X0621Y00893*
X06211Y00893*
X06211Y00893*
X06212*
X06212Y00893*
X06213Y00893*
Y00893*
Y00894*
Y00894*
Y00895*
Y00895*
Y00896*
Y00896*
Y00897*
Y00897*
Y00898*
Y00899*
Y00899*
Y009*
Y009*
Y00901*
Y00901*
Y00902*
Y00902*
Y00903*
Y00903*
Y00904*
Y00905*
Y00905*
Y00906*
Y00906*
Y00907*
Y00907*
Y00908*
Y00908*
Y00909*
Y00909*
Y0091*
Y0091*
Y00911*
Y00912*
Y00912*
Y00913*
Y00913*
X06212*
X06212Y00913*
X06211Y00913*
X06211Y00913*
X0621Y00913*
X0621*
G37*
G36*
X06307D02*
X06303D01*
X06303Y00913*
X06303Y00913*
X06303Y00913*
X06303Y00913*
X06302Y00913*
X06302Y00912*
X06302Y00912*
X06301Y00912*
X06301Y00912*
X06301Y00911*
X06301Y00911*
X06301Y00911*
X063Y00911*
X063Y0091*
X063Y0091*
X063Y0091*
X06299Y0091*
X06299Y00909*
X06299Y00909*
X06299Y00909*
X06298Y00908*
X06298Y00908*
X06298Y00908*
X06297Y00908*
X06297Y00907*
X06297Y00907*
X06297Y00907*
X06296Y00907*
X06296Y00906*
X06296Y00906*
X06296Y00906*
X06295Y00905*
X06295Y00905*
X06295Y00905*
X06295Y00905*
X06294Y00905*
X06294Y00905*
X06294Y00904*
X06294Y00904*
X06294Y00904*
X06293Y00904*
X06293Y00903*
X06293Y00903*
X06293Y00903*
X06292Y00903*
X06292Y00902*
X06292Y00902*
X06291Y00902*
X06291Y00901*
X06291Y00901*
X06291Y00901*
X06291Y00901*
X0629Y00901*
X0629Y009*
X0629Y009*
X0629Y009*
X0629Y009*
X06289Y009*
X06289Y00899*
X06289Y00899*
X06289Y00899*
X06289Y00899*
X06288Y00899*
X06288Y00898*
X06288Y00898*
X06288Y00898*
X06287Y00898*
X06287Y00897*
X06287Y00897*
X06287Y00897*
X06286Y00897*
X06286Y00896*
X06286Y00896*
X06286Y00896*
X06286Y00896*
X06285Y00895*
X06285Y00895*
X06285Y00895*
X06299*
X063Y00895*
X063Y00895*
X06301Y00895*
X06301Y00894*
X06302Y00894*
X06302Y00894*
X06303Y00893*
X06303Y00893*
X06303Y00893*
X06303Y00892*
X06303Y00892*
X06303Y00891*
Y0089*
Y0089*
Y00889*
Y00889*
Y00888*
Y00888*
Y00887*
Y00887*
Y00886*
Y00886*
Y00885*
Y00885*
Y00884*
Y00883*
Y00883*
Y00882*
Y00882*
Y00881*
Y00881*
Y0088*
Y0088*
Y00879*
Y00879*
Y00878*
Y00877*
Y00877*
Y00876*
Y00876*
Y00875*
Y00875*
Y00874*
Y00874*
Y00873*
Y00873*
Y00872*
Y00872*
Y00871*
Y0087*
Y0087*
Y00869*
Y00869*
Y00868*
Y00868*
Y00867*
Y00867*
Y00866*
Y00866*
Y00865*
Y00865*
Y00864*
Y00863*
Y00863*
Y00862*
Y00862*
Y00861*
X06303Y00861*
X06303Y0086*
X06303Y0086*
X06303Y00859*
X06303Y00859*
X06302Y00858*
X06302Y00858*
X06301Y00858*
X06301Y00858*
X063Y00857*
X063Y00857*
X06299Y00857*
X0626*
X06259Y00857*
X06259Y00857*
X06258Y00858*
X06258Y00858*
X06258Y00858*
X06257Y00858*
X06257Y00859*
X06257Y00859*
X06256Y0086*
X06256Y0086*
X06256Y00861*
X06256Y00861*
Y00862*
Y00862*
Y00863*
Y00863*
Y00864*
X06256Y00863*
X06256Y00863*
X06255Y00863*
X06255Y00863*
X06255Y00862*
X06254Y00862*
X06254Y00862*
X06254Y00862*
X06254Y00861*
X06254Y00861*
X06253Y00861*
X06253Y00861*
X06253Y0086*
X06253Y0086*
X06252Y0086*
X06252Y0086*
X06252Y00859*
X06251Y00859*
X06251Y00859*
X06251Y00858*
X06251Y00858*
X0625Y00858*
X0625Y00858*
X0625Y00857*
X0625Y00857*
X06249Y00857*
X06249Y00857*
X06249Y00857*
X06249Y00856*
X06248Y00856*
X06248Y00856*
X06248Y00855*
X06248Y00855*
X06247Y00855*
X06247Y00855*
X06247Y00854*
X06247Y00854*
X06246Y00854*
X06246Y00854*
X06246Y00853*
X06246Y00853*
X06245Y00853*
X06245Y00852*
X06245Y00852*
X06244Y00852*
X06244Y00852*
X06244Y00851*
X06244Y00851*
X06243Y00851*
X06243Y00851*
X06243Y0085*
X06243Y0085*
X06243Y0085*
X06242Y0085*
X06242Y0085*
X06242Y00849*
X06241Y00849*
X06241Y00849*
X06241Y00848*
X06241Y00848*
X06241Y00848*
X0624Y00848*
X0624Y00848*
X0624Y00848*
X0624Y00847*
X0624Y00847*
X06239Y00847*
X06239Y00847*
X06239Y00846*
X06238Y00846*
X06238Y00846*
X06238Y00845*
X06238Y00845*
X06238Y00845*
X06237Y00845*
X06237Y00845*
X06237Y00844*
X06236Y00844*
X06236Y00844*
X06236Y00844*
X06236Y00844*
X06235Y00843*
X06235Y00843*
X06235Y00843*
X06234Y00843*
X06234Y00842*
X06234Y00842*
Y00842*
Y00841*
Y00841*
Y0084*
Y0084*
Y00839*
Y00839*
Y00838*
Y00837*
Y00837*
Y00836*
Y00836*
Y00835*
Y00835*
Y00834*
Y00834*
Y00833*
Y00833*
Y00832*
Y00832*
Y00831*
Y0083*
Y0083*
Y00829*
Y00829*
Y00828*
Y00828*
Y00827*
Y00827*
Y00826*
Y00826*
Y00825*
Y00825*
Y00824*
Y00823*
Y00823*
Y00822*
Y00822*
Y00821*
Y00821*
Y0082*
Y0082*
Y00819*
Y00819*
Y00818*
Y00817*
Y00817*
Y00816*
Y00816*
Y00815*
Y00815*
Y00814*
Y00814*
Y00813*
Y00813*
Y00812*
Y00812*
Y00811*
Y0081*
Y0081*
Y00809*
Y00809*
Y00808*
Y00808*
Y00807*
Y00807*
Y00806*
Y00806*
Y00805*
Y00805*
Y00804*
Y00804*
X06234Y00804*
X06256*
X06256*
X06256Y00804*
X06256Y00804*
X06256*
Y00804*
Y00805*
Y00805*
Y00806*
Y00806*
Y00807*
Y00807*
Y00808*
Y00808*
Y00809*
Y00809*
Y0081*
Y0081*
Y00811*
Y00812*
Y00812*
Y00813*
Y00813*
Y00814*
Y00814*
Y00815*
Y00815*
Y00816*
Y00816*
Y00817*
Y00817*
Y00818*
Y00819*
Y00819*
Y0082*
Y0082*
Y00821*
Y00821*
Y00822*
Y00822*
Y00823*
Y00823*
Y00824*
Y00825*
Y00825*
Y00826*
Y00826*
Y00827*
Y00827*
Y00828*
Y00828*
Y00829*
Y00829*
Y0083*
Y0083*
Y00831*
Y00832*
Y00832*
Y00833*
Y00833*
Y00834*
Y00834*
X06256Y00835*
X06256Y00835*
X06256Y00836*
X06257Y00836*
X06257Y00837*
X06257Y00837*
X06257Y00837*
X06257Y00838*
X06258Y00838*
X06258Y00839*
X06259Y00839*
X06259Y00839*
X06259Y00839*
X06259Y00839*
X0626Y00839*
X0626Y0084*
X06261Y0084*
X06261Y0084*
X06262Y0084*
X06298*
X06298Y0084*
X06299Y0084*
X06299Y0084*
X063Y00839*
X063Y00839*
X063Y00839*
X06301Y00839*
X06301Y00839*
X06302Y00838*
X06302Y00838*
X06302Y00837*
X06303Y00837*
X06303Y00837*
X06303Y00836*
X06303Y00836*
X06303Y00835*
X06303Y00835*
X06303Y00834*
Y00834*
Y00833*
Y00833*
Y00832*
Y00832*
Y00831*
Y0083*
Y0083*
Y00829*
Y00829*
Y00828*
Y00828*
Y00827*
Y00827*
Y00826*
Y00826*
Y00825*
Y00825*
Y00824*
Y00823*
Y00823*
Y00822*
Y00822*
Y00821*
Y00821*
Y0082*
Y0082*
Y00819*
Y00819*
Y00818*
Y00817*
Y00817*
Y00816*
Y00816*
Y00815*
Y00815*
Y00814*
Y00814*
Y00813*
Y00813*
Y00812*
Y00812*
Y00811*
Y0081*
Y0081*
Y00809*
Y00809*
Y00808*
Y00808*
Y00807*
Y00807*
Y00806*
Y00806*
Y00805*
Y00805*
Y00804*
Y00804*
X06304Y00804*
X06325*
X06325*
X06325Y00804*
X06325Y00804*
X06325*
Y00804*
Y00805*
Y00805*
Y00806*
Y00806*
Y00807*
Y00807*
Y00808*
Y00808*
Y00809*
Y00809*
Y0081*
Y0081*
Y00811*
Y00812*
Y00812*
Y00813*
Y00813*
Y00814*
Y00814*
Y00815*
Y00815*
Y00816*
Y00816*
Y00817*
Y00817*
Y00818*
Y00819*
Y00819*
Y0082*
Y0082*
Y00821*
Y00821*
Y00822*
Y00822*
Y00823*
Y00823*
Y00824*
Y00825*
Y00825*
Y00826*
Y00826*
Y00827*
Y00827*
Y00828*
Y00828*
Y00829*
Y00829*
Y0083*
Y0083*
Y00831*
Y00832*
Y00832*
Y00833*
Y00833*
Y00834*
Y00834*
Y00835*
Y00835*
Y00836*
Y00836*
Y00837*
Y00837*
Y00838*
Y00839*
Y00839*
Y0084*
Y0084*
Y00841*
Y00841*
Y00842*
Y00842*
Y00843*
Y00843*
Y00844*
Y00845*
Y00845*
Y00846*
Y00846*
Y00847*
Y00847*
Y00848*
Y00848*
Y00849*
Y00849*
Y0085*
Y0085*
Y00851*
Y00852*
Y00852*
Y00853*
Y00853*
Y00854*
Y00854*
Y00855*
Y00855*
Y00856*
Y00856*
Y00857*
Y00857*
Y00858*
Y00859*
Y00859*
Y0086*
Y0086*
Y00861*
Y00861*
Y00862*
Y00862*
Y00863*
Y00863*
Y00864*
Y00865*
Y00865*
Y00866*
Y00866*
Y00867*
Y00867*
Y00868*
Y00868*
Y00869*
Y00869*
Y0087*
Y0087*
Y00871*
Y00872*
Y00872*
Y00873*
Y00873*
Y00874*
Y00874*
Y00875*
Y00875*
Y00876*
Y00876*
Y00877*
Y00877*
Y00878*
Y00879*
Y00879*
Y0088*
Y0088*
Y00881*
Y00881*
Y00882*
Y00882*
Y00883*
Y00883*
Y00884*
Y00885*
Y00885*
Y00886*
Y00886*
Y00887*
Y00887*
Y00888*
Y00888*
Y00889*
Y00889*
Y0089*
Y0089*
Y00891*
Y00892*
Y00892*
Y00893*
Y00893*
Y00894*
Y00894*
Y00895*
Y00895*
X06325Y00895*
X06325Y00895*
X06325Y00896*
X06325Y00896*
X06325Y00897*
Y00897*
X06325*
X06324Y00898*
X06324Y00898*
X06324Y00898*
X06324Y00899*
X06324Y00899*
X06323Y00899*
X06323Y00899*
X06323Y009*
X06323Y009*
X06323Y009*
X06322Y009*
X06322Y00901*
X06322Y00901*
X06321Y00901*
X06321Y00901*
X06321Y00902*
X06321Y00902*
X0632Y00902*
X0632Y00902*
X0632Y00903*
X0632Y00903*
X0632Y00903*
X06319Y00903*
X06319Y00904*
X06319Y00904*
X06319Y00904*
X06318Y00904*
X06318Y00905*
X06318Y00905*
X06317Y00905*
X06317Y00905*
X06317Y00906*
X06317Y00906*
X06316Y00906*
X06316Y00907*
X06316Y00907*
X06316Y00907*
X06315Y00907*
X06315Y00908*
X06315Y00908*
X06314Y00908*
X06314Y00908*
X06314Y00909*
X06314Y00909*
X06313Y00909*
X06313Y0091*
X06313Y0091*
X06313Y0091*
X06312Y0091*
X06312Y00911*
X06312Y00911*
X06312Y00911*
X06311Y00911*
X06311Y00912*
X06311Y00912*
X06311Y00912*
X0631Y00912*
X0631Y00912*
X0631Y00913*
X06309Y00913*
X06309Y00913*
X06309Y00913*
X06309*
X06308Y00913*
X06308Y00913*
X06307Y00913*
X06307Y00913*
X06307*
G37*
G36*
X06269Y01105D02*
X06266D01*
Y01105*
Y01105*
Y01104*
Y01103*
Y01103*
Y01102*
Y01102*
Y01101*
Y01101*
Y011*
Y011*
Y01099*
Y01099*
Y01098*
Y01098*
Y01097*
Y01096*
Y01096*
Y01095*
Y01095*
Y01094*
Y01094*
Y01093*
Y01093*
Y01092*
Y01092*
Y01091*
Y01091*
Y0109*
Y01089*
Y01089*
Y01088*
Y01088*
Y01087*
Y01087*
Y01086*
Y01086*
Y01085*
Y01085*
Y01084*
Y01083*
Y01083*
Y01082*
Y01082*
Y01081*
Y01081*
Y0108*
Y0108*
Y01079*
Y01079*
Y01078*
Y01078*
Y01077*
Y01076*
Y01076*
Y01075*
Y01075*
Y01074*
Y01074*
Y01073*
Y01073*
Y01072*
Y01072*
Y01071*
Y0107*
Y0107*
Y01069*
Y01069*
Y01068*
Y01068*
Y01067*
Y01067*
Y01066*
Y01066*
Y01065*
Y01065*
Y01064*
Y01063*
Y01063*
Y01062*
Y01062*
Y01061*
Y01061*
Y0106*
Y0106*
Y01059*
Y01059*
Y01058*
Y01058*
Y01057*
Y01056*
Y01056*
Y01055*
Y01055*
Y01054*
Y01054*
Y01053*
Y01053*
Y01052*
Y01052*
Y01051*
Y0105*
Y0105*
Y01049*
Y01049*
Y01048*
Y01048*
Y01047*
Y01047*
Y01046*
Y01046*
Y01045*
Y01045*
Y01044*
Y01043*
Y01043*
Y01042*
Y01042*
Y01041*
Y01041*
Y0104*
Y0104*
Y01039*
Y01039*
Y01038*
Y01038*
Y01037*
Y01036*
Y01036*
Y01035*
Y01035*
Y01034*
Y01034*
Y01033*
Y01033*
Y01032*
Y01032*
Y01031*
Y0103*
Y0103*
Y01029*
Y01029*
Y01028*
Y01028*
Y01027*
Y01027*
Y01026*
Y01026*
Y01025*
Y01025*
Y01024*
Y01023*
Y01023*
Y01022*
Y01022*
Y01021*
Y01021*
Y0102*
Y0102*
Y01019*
Y01019*
Y01018*
Y01018*
Y01017*
Y01016*
Y01016*
Y01015*
Y01015*
Y01014*
Y01014*
Y01013*
Y01013*
Y01012*
Y01012*
Y01011*
Y0101*
Y0101*
Y01009*
Y01009*
Y01008*
Y01008*
Y01007*
Y01007*
Y01006*
Y01006*
Y01005*
Y01005*
Y01004*
Y01003*
Y01003*
Y01002*
Y01002*
Y01001*
Y01001*
Y01*
Y01*
Y00999*
Y00999*
Y00998*
Y00998*
Y00997*
Y00996*
Y00996*
Y00995*
Y00995*
Y00994*
Y00994*
Y00993*
Y00993*
Y00992*
Y00992*
Y00991*
Y0099*
Y0099*
Y00989*
Y00989*
Y00988*
Y00988*
Y00987*
Y00987*
Y00986*
Y00986*
Y00985*
Y00985*
Y00984*
Y00983*
Y00983*
Y00982*
Y00982*
Y00981*
Y00981*
Y0098*
Y0098*
Y00979*
Y00979*
Y00978*
Y00978*
Y00977*
Y00976*
Y00976*
Y00975*
Y00975*
Y00974*
Y00974*
Y00973*
Y00973*
Y00972*
Y00972*
Y00971*
Y0097*
Y0097*
Y00969*
Y00969*
Y00968*
Y00968*
Y00967*
Y00967*
Y00966*
Y00966*
Y00965*
Y00965*
Y00964*
Y00963*
Y00963*
Y00962*
Y00962*
Y00961*
Y00961*
Y0096*
Y0096*
Y00959*
Y00959*
Y00958*
Y00958*
Y00957*
Y00956*
Y00956*
Y00955*
Y00955*
Y00954*
Y00954*
Y00953*
Y00953*
Y00952*
Y00952*
Y00951*
Y0095*
Y0095*
Y00949*
Y00949*
Y00948*
Y00948*
Y00947*
Y00947*
Y00946*
Y00946*
Y00945*
Y00945*
Y00944*
Y00943*
Y00943*
Y00942*
Y00942*
Y00941*
Y00941*
Y0094*
Y0094*
Y00939*
Y00939*
Y00938*
Y00938*
Y00937*
Y00936*
Y00936*
Y00935*
Y00935*
Y00934*
Y00934*
Y00933*
Y00933*
Y00932*
Y00932*
Y00931*
Y0093*
X06266Y0093*
X06265Y00929*
X06265Y00929*
X06265Y00928*
X06265Y00928*
X06264Y00928*
X06264Y00927*
X06264Y00927*
X06264Y00927*
X06263Y00927*
X06263Y00926*
X06263Y00926*
X06263Y00926*
X06262Y00925*
X06262Y00925*
X06262Y00925*
X06261Y00925*
X06261Y00924*
X06261Y00924*
X06261Y00924*
X06261Y00924*
X0626Y00924*
X0626Y00924*
X0626Y00923*
X0626Y00923*
X0626Y00923*
X06259Y00923*
X06259Y00922*
X06259Y00922*
X06259Y00922*
X06259Y00922*
X06258Y00921*
X06258Y00921*
X06258Y00921*
X06258Y00921*
X06258Y00921*
X06257Y00921*
X06257Y0092*
X06257Y0092*
X06257Y0092*
X06256Y0092*
X06256Y00919*
X06256Y00919*
X06256Y00919*
X06255Y00918*
X06255Y00918*
X06254Y00918*
X06254Y00918*
X06254Y00918*
X06254Y00917*
X06253Y00917*
X06253Y00917*
X06253Y00917*
X06253Y00916*
X06252Y00916*
X06252Y00916*
X06252Y00915*
X06251Y00915*
X06251Y00915*
X06251Y00915*
X06251Y00914*
X06251Y00914*
X0625Y00914*
X0625Y00914*
X0625Y00914*
X0625Y00914*
X0625Y00913*
X0625Y00913*
X06249Y00913*
X06249Y00913*
X06249Y00913*
X06248Y00912*
X06248Y00912*
X06248Y00912*
X06248Y00911*
X06247Y00911*
X06247Y00911*
X06247Y00911*
X06247Y0091*
X06246Y0091*
X06246Y0091*
X06246Y0091*
X06246Y0091*
X06246Y00909*
X06245Y00909*
X06245Y00909*
X06245Y00908*
X06244Y00908*
X06244Y00908*
X06244Y00908*
X06244Y00908*
X06244Y00907*
X06244Y00907*
X06243Y00907*
X06243Y00907*
X06243Y00907*
X06243Y00906*
X06242Y00906*
X06242Y00906*
X06242Y00905*
X06241Y00905*
X06241Y00905*
X06241Y00905*
X06241Y00905*
X06241Y00904*
X0624Y00904*
X0624Y00904*
X0624Y00904*
X0624Y00904*
X0624Y00903*
X06239Y00903*
X06239Y00903*
X06239Y00903*
X06239Y00903*
X06239Y00902*
X06238Y00902*
X06238Y00902*
X06238Y00902*
X06238Y00902*
X06238Y00901*
X06237Y00901*
X06237Y00901*
X06237Y00901*
X06237Y009*
X06236Y009*
X06236Y009*
X06236Y009*
X06236Y009*
X06236Y00899*
X06235Y00899*
X06235Y00899*
X06235Y00898*
X06234Y00898*
X06234Y00898*
X06234Y00898*
X06234Y00898*
X06234Y00897*
X06233Y00897*
X06233Y00897*
X06233Y00897*
X06233Y00897*
X06233Y00897*
X06233Y00896*
X06232Y00896*
X06232Y00896*
X06232Y00895*
X06231Y00895*
X06231Y00895*
X06231Y00895*
X06231Y00894*
X0623Y00894*
X0623Y00894*
X0623Y00894*
X0623Y00893*
X06229Y00893*
X06229Y00893*
X06229Y00893*
X06228Y00892*
X06228Y00892*
X06228Y00892*
X06228Y00892*
X06228Y00891*
X06227Y00891*
X06227Y00891*
X06227Y00891*
X06227Y0089*
X06226Y0089*
X06226Y0089*
X06226Y0089*
X06226Y00889*
X06225Y00889*
X06225Y00889*
X06225Y00888*
X06225Y00888*
X06224Y00888*
X06224Y00888*
X06224Y00888*
X06224Y00887*
X06223Y00887*
X06223Y00887*
X06223Y00887*
X06223Y00886*
X06222Y00886*
X06222Y00886*
X06222Y00885*
X06221Y00885*
X06221Y00885*
X06221Y00885*
X06221Y00885*
X06221Y00884*
X0622Y00884*
X0622Y00884*
X0622Y00884*
X0622Y00883*
X06219Y00883*
X06219Y00883*
X06219Y00883*
X06218Y00882*
X06218Y00882*
X06218Y00882*
X06217Y00881*
X06217Y00881*
X06217Y00881*
X06217Y00881*
X06216Y00881*
X06216Y0088*
X06216Y0088*
X06216Y0088*
X06215Y0088*
X06215Y00879*
X06215Y00879*
X06214Y00879*
X06214Y00878*
X06214Y00878*
X06214Y00878*
X06213Y00878*
X06213Y00878*
X06213Y00877*
X06213Y00877*
X06213Y00877*
X06212Y00877*
X06212Y00876*
X06212Y00876*
X06211Y00876*
X06211Y00875*
X06211Y00875*
X06211Y00875*
X0621Y00875*
X0621Y00875*
X0621Y00874*
X0621Y00874*
X0621Y00874*
X0621Y00874*
X06209Y00873*
X06209Y00873*
X06209Y00873*
X06209Y00872*
X06209Y00872*
X06209Y00872*
X06208Y00872*
X06208Y00871*
X06208Y00871*
X06208Y00871*
Y0087*
Y0087*
Y00869*
Y00869*
Y00868*
Y00868*
Y00867*
Y00867*
Y00866*
Y00866*
Y00865*
Y00865*
Y00864*
Y00863*
Y00863*
Y00862*
Y00862*
Y00861*
Y00861*
Y0086*
Y0086*
Y00859*
Y00859*
Y00858*
Y00857*
Y00857*
Y00856*
Y00856*
Y00855*
Y00855*
Y00854*
Y00854*
Y00853*
Y00853*
Y00852*
Y00852*
Y00851*
Y0085*
X06208Y0085*
X06208Y0085*
X06209Y00849*
X06209Y00849*
X06209Y00849*
X06209Y00849*
X06209Y00849*
X06209Y00848*
X0621Y00848*
X0621Y00847*
X0621Y00847*
X0621Y00847*
X0621Y00847*
X06211Y00847*
X06211Y00846*
X06211Y00846*
X06211Y00846*
X06211Y00846*
X06212Y00846*
X06212Y00847*
X06212Y00847*
X06212Y00847*
X06213Y00847*
X06213Y00847*
X06213Y00847*
X06213Y00848*
X06213Y00848*
X06214Y00848*
X06214Y00848*
X06214Y00848*
X06214Y00849*
X06214Y00849*
X06215Y00849*
X06215Y0085*
X06215Y0085*
X06216Y0085*
X06216Y0085*
X06216Y00851*
X06216Y00851*
X06217Y00851*
X06217Y00851*
X06217Y00852*
X06217Y00852*
X06218Y00852*
X06218Y00852*
X06218Y00852*
X06218Y00853*
X06219Y00853*
X06219Y00853*
X06219Y00854*
X06219Y00854*
X0622Y00854*
X0622Y00854*
X0622Y00854*
X0622Y00855*
X0622Y00855*
X06221Y00855*
X06221Y00855*
X06221Y00855*
X06221Y00856*
X06221Y00856*
X06221Y00856*
X06222Y00856*
X06222Y00857*
X06223Y00857*
X06223Y00857*
X06223Y00857*
X06223Y00857*
X06223Y00857*
X06224Y00858*
X06224Y00858*
X06224Y00858*
X06224Y00858*
X06225Y00859*
X06225Y00859*
X06225Y00859*
X06226Y0086*
X06226Y0086*
X06226Y0086*
X06226Y0086*
X06226Y0086*
X06227Y00861*
X06227Y00861*
X06227Y00861*
X06227Y00861*
X06227Y00861*
X06228Y00862*
X06228Y00862*
X06228Y00862*
X06229Y00862*
X06229Y00863*
X06229Y00863*
X06229Y00863*
X06229Y00863*
X0623Y00864*
X0623Y00864*
X0623Y00864*
X0623Y00864*
X06231Y00865*
X06231Y00865*
X06231Y00865*
X06231Y00865*
X06231Y00865*
X06232Y00866*
X06232Y00866*
X06232Y00866*
X06232Y00866*
X06233Y00867*
X06233Y00867*
X06233Y00867*
X06233Y00867*
X06233Y00867*
X06234Y00868*
X06234Y00868*
X06234Y00868*
X06234Y00868*
X06235Y00869*
X06235Y00869*
X06235Y00869*
X06235Y00869*
X06236Y0087*
X06236Y0087*
X06236Y0087*
X06236Y0087*
X06236Y0087*
X06237Y00871*
X06237Y00871*
X06237Y00871*
X06237Y00871*
X06237Y00871*
X06238Y00872*
X06238Y00872*
X06238Y00872*
X06238Y00872*
X06239Y00872*
X06239Y00873*
X06239Y00873*
X06239Y00873*
X06239Y00873*
X0624Y00874*
X0624Y00874*
X0624Y00874*
X0624Y00874*
X0624Y00874*
X0624Y00874*
X06241Y00875*
X06241Y00875*
X06241Y00875*
X06241Y00875*
X06242Y00876*
X06242Y00876*
X06242Y00876*
X06242Y00876*
X06242Y00876*
X06243Y00877*
X06243Y00877*
X06243Y00877*
X06243Y00877*
X06243Y00877*
X06244Y00878*
X06244Y00878*
X06244Y00878*
X06244Y00878*
X06244Y00878*
X06245Y00879*
X06245Y00879*
X06245Y00879*
X06245Y00879*
X06246Y0088*
X06246Y0088*
X06246Y0088*
X06246Y0088*
X06246Y0088*
X06247Y00881*
X06247Y00881*
X06247Y00881*
X06247Y00881*
X06247Y00881*
X06248Y00882*
X06248Y00882*
X06248Y00882*
X06248Y00882*
X06249Y00882*
X06249Y00883*
X06249Y00883*
X06249Y00883*
X06249Y00883*
X0625Y00884*
X0625Y00884*
X0625Y00884*
X0625Y00884*
X06251Y00885*
X06251Y00885*
X06251Y00885*
X06251Y00885*
X06251Y00885*
X06252Y00886*
X06252Y00886*
X06252Y00886*
X06253Y00887*
X06253Y00887*
X06253Y00887*
X06253Y00887*
X06254Y00888*
X06254Y00888*
X06254Y00888*
X06254Y00888*
X06255Y00889*
X06255Y00889*
X06255Y00889*
X06255Y00889*
X06255Y00889*
X06256Y0089*
X06256Y0089*
X06256Y0089*
X06256Y0089*
X06257Y00891*
X06257Y00891*
X06257Y00891*
X06257Y00891*
X06257Y00891*
X06258Y00891*
X06258Y00892*
X06258Y00892*
X06258Y00892*
X06258Y00892*
X06258Y00892*
X06259Y00892*
X06259Y00893*
X06259Y00893*
X06259Y00893*
X0626Y00894*
X0626Y00894*
X0626Y00894*
X0626Y00894*
X06261Y00895*
X06261Y00895*
X06261Y00895*
X06261Y00895*
X06261Y00895*
X06261Y00895*
X06262Y00896*
X06262Y00896*
X06262Y00896*
X06263Y00897*
X06263Y00897*
X06263Y00897*
X06263Y00897*
X06264Y00898*
X06264Y00898*
X06264Y00898*
X06264Y00898*
X06265Y00899*
X06265Y00899*
X06265Y00899*
X06265Y00899*
X06266Y009*
X06266Y009*
X06266Y009*
X06266Y009*
X06266Y009*
X06266Y009*
X06267Y00901*
X06267Y00901*
X06267Y00901*
X06267Y00901*
X06267Y00901*
X06268Y00902*
X06268Y00902*
X06269Y00902*
X06269Y00902*
X06269Y00902*
X06269Y00902*
X06269Y00903*
X06269Y00903*
X0627Y00903*
X0627Y00903*
X0627Y00904*
X0627Y00904*
X06271Y00904*
X06271Y00904*
X06271Y00905*
X06271Y00905*
X06272Y00905*
X06272Y00905*
X06272Y00905*
X06272Y00906*
X06272Y00906*
X06273Y00906*
X06273Y00906*
X06273Y00906*
X06273Y00907*
X06273Y00907*
X06274Y00907*
X06274Y00907*
X06274Y00907*
X06274Y00907*
X06274Y00908*
X06274Y00908*
X06275Y00908*
X06275Y00908*
X06275Y00908*
X06275Y00909*
X06276Y00909*
X06276Y00909*
X06276Y0091*
X06276Y0091*
X06277Y0091*
X06277Y0091*
X06277Y0091*
X06277Y0091*
X06277Y00911*
X06277Y00911*
X06278Y00911*
X06278Y00911*
X06278Y00912*
X06278Y00912*
X06279Y00912*
X06279Y00912*
X06279Y00912*
X06279Y00913*
X0628Y00913*
X0628Y00913*
X0628Y00913*
X0628Y00914*
X0628Y00914*
X06281Y00914*
X06281Y00914*
X06281Y00915*
X06281Y00915*
X06282Y00915*
X06282Y00915*
X06282Y00916*
X06282Y00916*
X06283Y00916*
X06283Y00916*
X06283Y00916*
X06283Y00917*
X06283Y00917*
X06283Y00917*
X06284Y00917*
X06284Y00917*
X06284Y00917*
X06284Y00918*
X06284Y00918*
X06285Y00919*
X06285Y00919*
X06285Y00919*
X06285Y00919*
X06285Y0092*
X06285Y0092*
X06285Y0092*
X06285Y0092*
X06286Y00921*
X06286Y00921*
X06286Y00921*
X06286Y00922*
Y00922*
Y00922*
X06286Y00922*
X06286Y00923*
X06287Y00923*
X06287Y00924*
Y00924*
Y00925*
Y00925*
Y00926*
Y00926*
Y00927*
Y00927*
Y00928*
Y00928*
Y00929*
Y00929*
Y0093*
Y0093*
Y00931*
Y00932*
Y00932*
Y00933*
Y00933*
Y00934*
Y00934*
Y00935*
Y00935*
Y00936*
Y00936*
Y00937*
Y00938*
Y00938*
Y00939*
Y00939*
Y0094*
Y0094*
Y00941*
Y00941*
Y00942*
Y00942*
Y00943*
Y00943*
Y00944*
Y00945*
Y00945*
Y00946*
Y00946*
Y00947*
Y00947*
Y00948*
Y00948*
Y00949*
Y00949*
Y0095*
Y0095*
Y00951*
Y00952*
Y00952*
Y00953*
Y00953*
Y00954*
Y00954*
Y00955*
Y00955*
Y00956*
Y00956*
Y00957*
Y00958*
Y00958*
Y00959*
Y00959*
Y0096*
Y0096*
Y00961*
Y00961*
Y00962*
Y00962*
Y00963*
Y00963*
Y00964*
Y00965*
Y00965*
Y00966*
Y00966*
Y00967*
Y00967*
Y00968*
Y00968*
Y00969*
Y00969*
Y0097*
Y0097*
Y00971*
Y00972*
Y00972*
Y00973*
Y00973*
Y00974*
Y00974*
Y00975*
Y00975*
Y00976*
Y00976*
Y00977*
Y00978*
Y00978*
Y00979*
Y00979*
Y0098*
Y0098*
Y00981*
Y00981*
Y00982*
Y00982*
Y00983*
Y00983*
Y00984*
Y00985*
Y00985*
Y00986*
Y00986*
Y00987*
Y00987*
Y00988*
Y00988*
Y00989*
Y00989*
Y0099*
Y0099*
Y00991*
Y00992*
Y00992*
Y00993*
Y00993*
Y00994*
Y00994*
Y00995*
Y00995*
Y00996*
Y00996*
Y00997*
Y00998*
Y00998*
Y00999*
Y00999*
Y01*
Y01*
Y01001*
Y01001*
Y01002*
Y01002*
Y01003*
Y01003*
Y01004*
Y01005*
Y01005*
Y01006*
Y01006*
Y01007*
Y01007*
Y01008*
Y01008*
Y01009*
Y01009*
Y0101*
Y0101*
Y01011*
Y01012*
Y01012*
Y01013*
Y01013*
Y01014*
Y01014*
Y01015*
Y01015*
Y01016*
Y01016*
Y01017*
Y01018*
Y01018*
Y01019*
Y01019*
Y0102*
Y0102*
Y01021*
Y01021*
Y01022*
Y01022*
Y01023*
Y01023*
Y01024*
Y01025*
Y01025*
Y01026*
Y01026*
Y01027*
Y01027*
Y01028*
Y01028*
Y01029*
Y01029*
Y0103*
Y0103*
Y01031*
Y01032*
Y01032*
Y01033*
Y01033*
Y01034*
Y01034*
Y01035*
Y01035*
Y01036*
Y01036*
Y01037*
Y01038*
Y01038*
Y01039*
Y01039*
Y0104*
Y0104*
Y01041*
Y01041*
Y01042*
Y01042*
Y01043*
Y01043*
Y01044*
Y01045*
Y01045*
Y01046*
Y01046*
Y01047*
Y01047*
Y01048*
Y01048*
Y01049*
Y01049*
Y0105*
Y0105*
Y01051*
Y01052*
Y01052*
Y01053*
Y01053*
Y01054*
Y01054*
Y01055*
Y01055*
Y01056*
Y01056*
Y01057*
Y01058*
Y01058*
Y01059*
Y01059*
Y0106*
Y0106*
Y01061*
Y01061*
Y01062*
Y01062*
Y01063*
Y01063*
Y01064*
Y01065*
Y01065*
Y01066*
Y01066*
Y01067*
Y01067*
Y01068*
Y01068*
Y01069*
Y01069*
Y0107*
Y0107*
Y01071*
Y01072*
Y01072*
Y01073*
Y01073*
Y01074*
Y01074*
Y01075*
Y01075*
Y01076*
Y01076*
Y01077*
Y01078*
Y01078*
Y01079*
Y01079*
Y0108*
Y0108*
Y01081*
Y01081*
Y01082*
Y01082*
Y01083*
Y01083*
Y01084*
Y01085*
Y01085*
Y01086*
Y01086*
Y01087*
Y01087*
Y01088*
Y01088*
X06287Y01088*
X06286Y01089*
X06286Y01089*
X06286Y0109*
Y0109*
X06286Y01091*
X06286Y01091*
X06286Y01091*
X06286Y01091*
X06285Y01091*
X06285Y01092*
X06285Y01092*
X06285Y01092*
X06284Y01092*
X06284Y01093*
X06284Y01093*
X06284Y01093*
X06284Y01093*
X06283Y01093*
X06283Y01094*
X06283Y01094*
X06283Y01094*
X06282Y01094*
X06282Y01095*
X06282Y01095*
X06281Y01095*
X06281Y01096*
X06281Y01096*
X06281Y01096*
X06281Y01096*
X0628Y01096*
X0628Y01097*
X0628Y01097*
X0628Y01097*
X06279Y01097*
X06279Y01098*
X06279Y01098*
X06279Y01098*
X06279Y01098*
X06278Y01098*
X06278Y01099*
X06278Y01099*
X06278Y01099*
X06277Y01099*
X06277Y011*
X06277Y011*
X06277Y011*
X06277Y011*
X06276Y011*
X06276Y01101*
X06276Y01101*
X06276Y01101*
X06275Y01101*
X06275Y01102*
X06275Y01102*
X06274Y01102*
X06274Y01103*
X06274Y01103*
X06274Y01103*
X06273Y01103*
X06273Y01103*
X06273Y01104*
X06273Y01104*
X06273Y01104*
X06273Y01104*
X06272Y01104*
X06272Y01105*
X06272Y01105*
X06272Y01105*
X06272Y01105*
X06271*
X06271*
X06271Y01105*
X0627Y01105*
X0627Y01105*
X06269Y01105*
G37*
G36*
X06531Y00913D02*
X0646D01*
X0646Y00913*
X0646Y00913*
X0646Y00913*
Y00913*
Y00912*
Y00912*
Y00911*
Y0091*
Y0091*
Y00909*
Y00909*
Y00908*
Y00908*
Y00907*
Y00907*
Y00906*
Y00906*
Y00905*
Y00905*
Y00904*
Y00903*
Y00903*
Y00902*
Y00902*
Y00901*
Y00901*
Y009*
Y009*
Y00899*
Y00899*
Y00898*
Y00897*
Y00897*
Y00896*
Y00896*
Y00895*
Y00895*
Y00894*
Y00894*
Y00893*
Y00893*
Y00892*
Y00892*
Y00891*
Y0089*
Y0089*
Y00889*
Y00889*
Y00888*
Y00888*
Y00887*
Y00887*
Y00886*
Y00886*
Y00885*
Y00885*
Y00884*
Y00883*
Y00883*
Y00882*
Y00882*
Y00881*
Y00881*
Y0088*
Y0088*
Y00879*
Y00879*
Y00878*
Y00877*
Y00877*
Y00876*
Y00876*
Y00875*
Y00875*
Y00874*
Y00874*
Y00873*
Y00873*
Y00872*
Y00872*
Y00871*
Y0087*
Y0087*
Y00869*
Y00869*
Y00868*
Y00868*
Y00867*
Y00867*
Y00866*
Y00866*
Y00865*
Y00865*
Y00864*
Y00863*
Y00863*
Y00862*
Y00862*
Y00861*
Y00861*
Y0086*
Y0086*
Y00859*
Y00859*
Y00858*
Y00857*
Y00857*
Y00856*
Y00856*
Y00855*
Y00855*
Y00854*
Y00854*
Y00853*
Y00853*
Y00852*
Y00852*
Y00851*
Y0085*
Y0085*
Y00849*
Y00849*
Y00848*
Y00848*
Y00847*
Y00847*
Y00846*
Y00846*
Y00845*
Y00845*
Y00844*
Y00843*
Y00843*
Y00842*
Y00842*
Y00841*
Y00841*
Y0084*
Y0084*
Y00839*
Y00839*
Y00838*
Y00837*
Y00837*
Y00836*
Y00836*
Y00835*
Y00835*
Y00834*
Y00834*
Y00833*
Y00833*
Y00832*
Y00832*
Y00831*
Y0083*
Y0083*
Y00829*
Y00829*
Y00828*
Y00828*
Y00827*
Y00827*
Y00826*
Y00826*
Y00825*
Y00825*
Y00824*
Y00823*
Y00823*
Y00822*
Y00822*
Y00821*
Y00821*
Y0082*
Y0082*
Y00819*
Y00819*
Y00818*
Y00817*
Y00817*
Y00816*
Y00816*
Y00815*
Y00815*
Y00814*
Y00814*
Y00813*
Y00813*
Y00812*
Y00812*
Y00811*
Y0081*
Y0081*
Y00809*
Y00809*
Y00808*
Y00808*
Y00807*
Y00807*
Y00806*
Y00806*
Y00805*
Y00805*
Y00804*
Y00804*
X06533*
X06533*
X06533Y00804*
X06534Y00804*
X06534Y00804*
X06535Y00804*
X06535*
X06535Y00804*
X06535Y00804*
X06535Y00804*
X06536Y00805*
X06536Y00805*
X06536Y00805*
X06536Y00805*
X06536Y00805*
X06536Y00806*
X06537Y00806*
X06537Y00806*
X06537Y00806*
X06537Y00806*
X06537Y00807*
X06538Y00807*
X06538Y00807*
X06538Y00807*
X06538Y00807*
X06539Y00808*
X06539Y00808*
X06539Y00808*
X06539Y00808*
X06539Y00808*
X06539Y00808*
X0654Y00809*
X0654Y00809*
X0654Y00809*
X0654Y0081*
X06541Y0081*
X06541Y0081*
X06541Y0081*
X06541Y0081*
X06542Y00811*
X06542Y00811*
X06542Y00811*
X06542Y00811*
X06542Y00811*
X06543Y00812*
X06543Y00812*
X06543Y00812*
X06543Y00812*
X06543Y00812*
X06543Y00812*
X06544Y00813*
X06544Y00813*
X06544Y00813*
X06544Y00813*
X06545Y00814*
X06545Y00814*
X06545Y00814*
X06545Y00814*
X06545Y00814*
X06546Y00815*
X06546Y00815*
X06546Y00815*
X06546Y00815*
X06546Y00815*
X06546Y00815*
X06547Y00816*
X06547Y00816*
X06547Y00816*
X06547Y00817*
X06548Y00817*
X06548Y00817*
X06548Y00817*
X06549Y00818*
X06549Y00818*
X06549Y00818*
X06549Y00818*
X0655Y00819*
X0655Y00819*
X0655Y00819*
X0655Y0082*
X0655Y0082*
Y0082*
X0655Y00821*
X0655Y00821*
X0655Y00822*
X06551Y00822*
X06551Y00822*
Y00822*
Y00823*
Y00823*
Y00824*
Y00825*
Y00825*
Y00826*
Y00826*
Y00827*
Y00827*
Y00828*
Y00828*
Y00829*
Y00829*
Y0083*
Y0083*
Y00831*
Y00832*
Y00832*
Y00833*
Y00833*
Y00834*
Y00834*
Y00835*
Y00835*
Y00836*
Y00836*
Y00837*
Y00837*
Y00838*
Y00839*
Y00839*
Y0084*
Y0084*
Y00841*
Y00841*
Y00842*
Y00842*
Y00843*
Y00843*
Y00844*
Y00845*
Y00845*
Y00846*
Y00846*
Y00847*
Y00847*
Y00848*
Y00848*
Y00849*
Y00849*
Y0085*
Y0085*
Y00851*
Y00852*
Y00852*
Y00853*
Y00853*
Y00854*
Y00854*
Y00855*
Y00855*
Y00856*
Y00856*
Y00857*
Y00857*
Y00858*
Y00859*
Y00859*
Y0086*
Y0086*
Y00861*
Y00861*
Y00862*
Y00862*
Y00863*
Y00863*
Y00864*
Y00865*
Y00865*
Y00866*
Y00866*
Y00867*
Y00867*
Y00868*
Y00868*
Y00869*
Y00869*
Y0087*
Y0087*
Y00871*
Y00872*
Y00872*
Y00873*
Y00873*
Y00874*
Y00874*
Y00875*
Y00875*
Y00876*
Y00876*
Y00877*
Y00877*
Y00878*
Y00879*
Y00879*
Y0088*
Y0088*
Y00881*
Y00881*
Y00882*
Y00882*
Y00883*
Y00883*
Y00884*
Y00885*
Y00885*
Y00886*
Y00886*
Y00887*
Y00887*
Y00888*
Y00888*
Y00889*
Y00889*
Y0089*
Y0089*
Y00891*
Y00892*
Y00892*
Y00893*
Y00893*
Y00894*
Y00894*
Y00895*
Y00895*
X06551Y00895*
X0655Y00895*
X0655Y00896*
X0655Y00896*
X0655Y00897*
Y00897*
X0655Y00898*
X0655Y00898*
X0655Y00898*
X06549Y00898*
X06549Y00898*
X06549Y00899*
X06549Y00899*
X06548Y00899*
X06548Y009*
X06548Y009*
X06547Y009*
X06547Y009*
X06547Y00901*
X06547Y00901*
X06547Y00901*
X06546Y00901*
X06546Y00901*
X06546Y00902*
X06546Y00902*
X06545Y00902*
X06545Y00902*
X06545Y00903*
X06545Y00903*
X06545Y00903*
X06544Y00903*
X06544Y00904*
X06544Y00904*
X06543Y00904*
X06543Y00904*
X06543Y00905*
X06543Y00905*
X06542Y00905*
X06542Y00905*
X06542Y00906*
X06542Y00906*
X06541Y00906*
X06541Y00906*
X06541Y00907*
X06541Y00907*
X0654Y00907*
X0654Y00907*
X0654Y00908*
X0654Y00908*
X0654Y00908*
X06539Y00908*
X06539Y00908*
X06539Y00909*
X06539Y00909*
X06538Y00909*
X06538Y0091*
X06538Y0091*
X06537Y0091*
X06537Y0091*
X06537Y00911*
X06537Y00911*
X06536Y00911*
X06536Y00911*
X06536Y00912*
X06536Y00912*
X06536Y00912*
X06535Y00912*
X06535Y00912*
X06535Y00913*
X06534Y00913*
X06534Y00913*
X06534Y00913*
X06533*
X06532Y00913*
X06532Y00913*
X06531Y00913*
X06531Y00913*
G37*
G36*
X06416D02*
X06345D01*
X06345Y00913*
X06345Y00913*
X06345Y00913*
X06345Y00912*
Y00912*
Y00912*
Y00912*
Y00911*
Y0091*
Y0091*
Y00909*
Y00909*
Y00908*
Y00908*
Y00907*
Y00907*
Y00906*
Y00906*
Y00905*
Y00905*
Y00904*
Y00903*
Y00903*
Y00902*
Y00902*
Y00901*
Y00901*
Y009*
Y009*
Y00899*
Y00899*
Y00898*
Y00897*
Y00897*
Y00896*
Y00896*
Y00895*
Y00895*
Y00894*
Y00894*
Y00893*
Y00893*
Y00892*
Y00892*
Y00891*
Y0089*
Y0089*
Y00889*
Y00889*
Y00888*
Y00888*
Y00887*
Y00887*
Y00886*
Y00886*
Y00885*
Y00885*
Y00884*
Y00883*
Y00883*
Y00882*
Y00882*
Y00881*
Y00881*
Y0088*
Y0088*
Y00879*
Y00879*
Y00878*
Y00877*
Y00877*
Y00876*
Y00876*
Y00875*
Y00875*
Y00874*
Y00874*
Y00873*
Y00873*
Y00872*
Y00872*
Y00871*
Y0087*
Y0087*
Y00869*
Y00869*
Y00868*
Y00868*
Y00867*
Y00867*
Y00866*
Y00866*
Y00865*
Y00865*
Y00864*
Y00863*
Y00863*
Y00862*
Y00862*
Y00861*
Y00861*
Y0086*
Y0086*
Y00859*
Y00859*
Y00858*
Y00857*
Y00857*
Y00856*
Y00856*
Y00855*
Y00855*
Y00854*
Y00854*
Y00853*
Y00853*
Y00852*
Y00852*
Y00851*
Y0085*
Y0085*
Y00849*
Y00849*
Y00848*
Y00848*
Y00847*
Y00847*
Y00846*
Y00846*
Y00845*
Y00845*
Y00844*
Y00843*
Y00843*
Y00842*
Y00842*
Y00841*
Y00841*
Y0084*
Y0084*
Y00839*
Y00839*
Y00838*
Y00837*
Y00837*
Y00836*
Y00836*
Y00835*
Y00835*
Y00834*
Y00834*
Y00833*
Y00833*
Y00832*
Y00832*
Y00831*
Y0083*
Y0083*
Y00829*
Y00829*
Y00828*
Y00828*
Y00827*
Y00827*
Y00826*
Y00826*
Y00825*
Y00825*
Y00824*
Y00823*
Y00823*
Y00822*
Y00822*
Y00821*
Y00821*
Y0082*
Y0082*
Y00819*
Y00819*
Y00818*
Y00817*
Y00817*
Y00816*
Y00816*
Y00815*
Y00815*
Y00814*
Y00814*
Y00813*
Y00813*
Y00812*
Y00812*
Y00811*
Y0081*
Y0081*
Y00809*
Y00809*
Y00808*
Y00808*
Y00807*
Y00807*
Y00806*
Y00806*
Y00805*
Y00805*
X06345Y00805*
X06345Y00804*
X06345Y00804*
X06345Y00804*
X06366*
X06367Y00804*
X06367Y00804*
X06367Y00804*
Y00804*
Y00805*
Y00805*
Y00806*
Y00806*
Y00807*
Y00807*
Y00808*
Y00808*
Y00809*
Y00809*
Y0081*
Y0081*
Y00811*
Y00812*
Y00812*
Y00813*
Y00813*
Y00814*
Y00814*
Y00815*
Y00815*
Y00816*
Y00816*
Y00817*
Y00817*
Y00818*
Y00819*
Y00819*
Y0082*
Y0082*
Y00821*
Y00821*
Y00822*
Y00822*
Y00823*
Y00823*
Y00824*
Y00825*
Y00825*
Y00826*
Y00826*
Y00827*
Y00827*
Y00828*
Y00828*
Y00829*
Y00829*
Y0083*
X06367Y0083*
X06366Y00831*
X06366Y00831*
X06366Y00832*
Y00832*
X06366Y00833*
X06366Y00833*
X06367Y00834*
X06367Y00834*
Y00834*
Y00834*
Y00835*
X06367Y00835*
X06367Y00836*
X06367Y00836*
X06367Y00837*
X06368Y00837*
X06368Y00838*
X06368Y00838*
X06369Y00838*
X06369Y00838*
X0637Y00839*
X0637Y00839*
X06371Y00839*
X06391*
X06392Y00839*
X06392Y00839*
X06393Y00838*
X06393Y00838*
X06394Y00838*
X06394Y00838*
X06395Y00837*
X06395Y00837*
X06395Y00836*
X06395Y00836*
X06395Y00836*
X06396Y00835*
X06396Y00835*
X06396Y00835*
X06396Y00835*
X06396Y00834*
X06397Y00834*
X06397Y00833*
X06397Y00833*
X06397Y00833*
X06397Y00832*
X06397Y00832*
X06398Y00832*
X06398Y00831*
X06398Y00831*
X06398Y00831*
X06399Y0083*
X06399Y0083*
X06399Y0083*
X06399Y00829*
X06399Y00829*
X06399Y00829*
X064Y00828*
X064Y00828*
X064Y00828*
X064Y00827*
X06401Y00827*
X06401Y00827*
X06401Y00826*
X06401Y00826*
X06401Y00826*
X06402Y00825*
X06402Y00825*
X06402Y00824*
X06402Y00824*
X06402Y00824*
X06402Y00824*
X06402Y00824*
X06403Y00823*
X06403Y00823*
X06403Y00823*
X06403Y00823*
X06403Y00822*
X06404Y00822*
X06404Y00821*
X06404Y00821*
X06404Y00821*
X06404Y0082*
X06405Y0082*
X06405Y0082*
X06405Y00819*
X06405Y00819*
X06405Y00819*
X06406Y00818*
X06406Y00818*
X06406Y00818*
X06406Y00817*
X06406Y00817*
X06406Y00817*
X06407Y00817*
X06407Y00816*
X06407Y00816*
X06407Y00815*
X06408Y00815*
X06408Y00815*
X06408Y00814*
X06408Y00814*
X06408Y00814*
X06409Y00813*
X06409Y00813*
X06409Y00813*
X06409Y00812*
X06409Y00812*
X0641Y00811*
X0641Y00811*
X0641Y00811*
X0641Y00811*
X06411Y0081*
X06411Y0081*
X06411Y0081*
X06411Y00809*
X06411Y00809*
X06411Y00809*
X06411Y00808*
X06411Y00808*
X06412Y00808*
X06412Y00808*
X06412Y00807*
X06412Y00807*
X06412Y00807*
X06413Y00807*
X06413Y00806*
X06413Y00806*
X06413Y00805*
X06413Y00805*
X06414Y00805*
X06414Y00805*
X06414Y00804*
X06414Y00804*
X06414Y00804*
X06415Y00804*
X06415Y00804*
X06415*
X06438*
X06437Y00804*
X06437Y00804*
X06437Y00804*
X06437Y00805*
X06437Y00805*
X06437Y00805*
X06437Y00805*
X06437Y00805*
X06436Y00806*
X06436Y00806*
X06436Y00807*
X06436Y00807*
X06435Y00807*
X06435Y00808*
X06435Y00808*
X06435Y00808*
X06435Y00808*
X06435Y00809*
X06434Y00809*
X06434Y00809*
X06434Y0081*
X06434Y0081*
X06434Y00811*
X06434Y00811*
X06434Y00811*
X06433Y00811*
X06433Y00811*
X06433Y00812*
X06433Y00812*
X06432Y00812*
X06432Y00813*
X06432Y00813*
X06432Y00813*
X06432Y00814*
X06431Y00814*
X06431Y00814*
X06431Y00815*
X06431Y00815*
X06431Y00815*
X0643Y00816*
X0643Y00816*
X0643Y00816*
X0643Y00817*
X0643Y00817*
X06429Y00818*
X06429Y00818*
X06429Y00818*
X06429Y00819*
X06429Y00819*
X06429Y00819*
X06429Y00819*
X06428Y00819*
X06428Y0082*
X06428Y0082*
X06428Y0082*
X06428Y00821*
X06427Y00821*
X06427Y00821*
X06427Y00822*
X06427Y00822*
X06427Y00822*
X06426Y00823*
X06426Y00823*
X06426Y00823*
X06426Y00823*
X06426Y00824*
X06426Y00824*
X06425Y00824*
X06425Y00824*
X06425Y00824*
X06425Y00825*
X06425Y00825*
X06424Y00826*
X06424Y00826*
X06424Y00826*
X06424Y00826*
X06424Y00827*
X06424Y00827*
X06424Y00827*
X06423Y00827*
X06423Y00828*
X06423Y00828*
X06423Y00829*
X06422Y00829*
X06422Y00829*
X06422Y0083*
X06422Y0083*
X06422Y00831*
X06422Y00831*
X06422Y00831*
X06421Y00831*
X06421Y00832*
X06421Y00832*
X06421Y00832*
X0642Y00833*
X0642Y00833*
X0642Y00833*
X0642Y00833*
X0642Y00834*
X0642Y00834*
X06419Y00834*
X06419Y00835*
X06419Y00835*
X06419Y00836*
X06419Y00836*
Y00837*
Y00837*
X06419Y00838*
X06419Y00839*
X06419Y00839*
X06419Y00839*
X0642Y0084*
X0642Y0084*
X0642Y00841*
Y00841*
X0642Y00841*
X06421Y00841*
X06421Y00841*
X06421Y00842*
X06422Y00842*
X06422Y00842*
X06422Y00842*
X06422Y00842*
X06422Y00843*
X06423Y00843*
X06423Y00843*
X06423Y00844*
X06423Y00844*
X06424Y00844*
X06424Y00844*
X06424Y00845*
X06424Y00845*
X06424Y00845*
X06425Y00845*
X06425Y00845*
X06425Y00846*
X06426Y00846*
X06426Y00846*
X06426Y00847*
X06426Y00847*
X06426Y00847*
X06427Y00847*
X06427Y00847*
X06427Y00848*
X06427Y00848*
X06428Y00848*
X06428Y00848*
X06428Y00849*
X06429Y00849*
X06429Y00849*
X06429Y0085*
X06429Y0085*
X0643Y0085*
X0643Y0085*
X0643Y00851*
X0643Y00851*
X06431Y00851*
X06431Y00851*
X06431Y00852*
X06431Y00852*
X06431Y00852*
X06431Y00852*
X06432Y00852*
X06432Y00853*
X06432Y00853*
X06432Y00853*
X06433Y00854*
X06433Y00854*
X06433Y00854*
X06433Y00854*
X06433Y00854*
X06433Y00854*
X06434Y00855*
X06434Y00855*
X06434Y00855*
X06434Y00855*
X06434Y00855*
X06435Y00855*
X06435Y00856*
X06435Y00856*
X06435Y00856*
X06435Y00857*
X06435Y00857*
X06435Y00857*
X06435Y00857*
Y00857*
Y00857*
Y00858*
Y00859*
Y00859*
Y0086*
Y0086*
Y00861*
Y00861*
Y00862*
Y00862*
Y00863*
Y00863*
Y00864*
Y00865*
Y00865*
Y00866*
Y00866*
Y00867*
Y00867*
Y00868*
Y00868*
Y00869*
Y00869*
Y0087*
Y0087*
Y00871*
Y00872*
Y00872*
Y00873*
Y00873*
Y00874*
Y00874*
Y00875*
Y00875*
Y00876*
Y00876*
Y00877*
Y00877*
Y00878*
Y00879*
Y00879*
Y0088*
Y0088*
Y00881*
Y00881*
Y00882*
Y00882*
Y00883*
Y00883*
Y00884*
Y00885*
Y00885*
Y00886*
Y00886*
Y00887*
Y00887*
Y00888*
Y00888*
Y00889*
Y00889*
Y0089*
Y0089*
Y00891*
Y00892*
Y00892*
Y00893*
Y00893*
Y00894*
Y00894*
Y00895*
Y00895*
Y00896*
Y00896*
X06435Y00897*
X06435Y00897*
X06435Y00898*
X06435Y00898*
X06435Y00898*
X06435Y00898*
X06435Y00898*
X06434Y00898*
X06434Y00899*
X06434Y00899*
X06434Y00899*
X06434Y00899*
X06433Y009*
X06433Y009*
X06433Y009*
X06433Y009*
X06432Y00901*
X06432Y00901*
X06432Y00901*
X06432Y00901*
X06432Y00901*
X06431Y00902*
X06431Y00902*
X06431Y00902*
X06431Y00902*
X0643Y00903*
X0643Y00903*
X0643Y00903*
X0643Y00903*
X06429Y00904*
X06429Y00904*
X06429Y00904*
X06429Y00904*
X06428Y00905*
X06428Y00905*
X06428Y00905*
X06428Y00905*
X06427Y00905*
X06427Y00906*
X06427Y00906*
X06427Y00906*
X06426Y00907*
X06426Y00907*
X06426Y00907*
X06426Y00907*
X06425Y00908*
X06425Y00908*
X06425Y00908*
X06424Y00908*
X06424Y00909*
X06424Y00909*
X06424Y00909*
X06423Y0091*
X06423Y0091*
X06423Y0091*
X06423Y0091*
X06422Y00911*
X06422Y00911*
X06422Y00911*
X06422Y00911*
X06421Y00912*
X06421Y00912*
X06421Y00912*
X06421Y00912*
X0642Y00912*
X0642Y00912*
X0642*
X0642Y00913*
X06419Y00913*
X06419Y00913*
Y00913*
X06418*
X06417Y00913*
X06417Y00913*
X06416Y00913*
X06416Y00913*
G37*
%LNtimingcard_pcb-3*%
%LPD*%
G36*
X06524Y00893D02*
X06525Y00893D01*
X06525Y00893*
X06526Y00892*
X06526Y00892*
X06526Y00892*
X06527Y00892*
X06527Y00891*
X06528Y00891*
X06528Y00891*
X06528Y0089*
X06529Y0089*
X06529Y00889*
X06529Y00889*
X06529Y00888*
Y00888*
Y00887*
Y00887*
Y00886*
Y00886*
Y00885*
Y00885*
Y00884*
Y00883*
Y00883*
Y00882*
Y00882*
Y00881*
Y00881*
Y0088*
Y0088*
Y00879*
Y00879*
Y00878*
Y00877*
Y00877*
Y00876*
Y00876*
Y00875*
Y00875*
Y00874*
Y00874*
Y00873*
Y00873*
Y00872*
Y00872*
Y00871*
Y0087*
Y0087*
Y00869*
Y00869*
Y00868*
Y00868*
Y00867*
Y00867*
Y00866*
Y00866*
Y00865*
Y00865*
Y00864*
Y00863*
Y00863*
Y00862*
Y00862*
Y00861*
Y00861*
Y0086*
Y0086*
Y00859*
Y00859*
Y00858*
Y00857*
Y00857*
Y00856*
Y00856*
Y00855*
Y00855*
Y00854*
Y00854*
Y00853*
Y00853*
Y00852*
Y00852*
Y00851*
Y0085*
Y0085*
Y00849*
Y00849*
Y00848*
Y00848*
Y00847*
Y00847*
Y00846*
Y00846*
Y00845*
Y00845*
Y00844*
Y00843*
Y00843*
Y00842*
Y00842*
Y00841*
Y00841*
Y0084*
Y0084*
Y00839*
Y00839*
Y00838*
Y00837*
Y00837*
Y00836*
Y00836*
Y00835*
Y00835*
Y00834*
Y00834*
Y00833*
Y00833*
Y00832*
Y00832*
Y00831*
Y0083*
Y0083*
Y00829*
Y00829*
Y00828*
X06529Y00828*
X06529Y00827*
X06529Y00827*
X06528Y00826*
X06528Y00826*
X06528Y00825*
X06527Y00825*
X06527Y00825*
X06526Y00825*
X06526Y00824*
X06525Y00824*
X06525Y00824*
X06485*
X06485Y00824*
X06484Y00824*
X06484Y00825*
X06483Y00825*
X06483Y00825*
X06483Y00825*
X06482Y00826*
X06482Y00826*
X06482Y00827*
X06482Y00827*
X06481Y00828*
X06481Y00828*
Y00829*
Y00829*
Y0083*
Y0083*
Y00831*
Y00832*
Y00832*
Y00833*
Y00833*
Y00834*
Y00834*
Y00835*
Y00835*
Y00836*
Y00836*
Y00837*
Y00837*
Y00838*
Y00839*
Y00839*
Y0084*
Y0084*
Y00841*
Y00841*
Y00842*
Y00842*
Y00843*
Y00843*
Y00844*
Y00845*
Y00845*
Y00846*
Y00846*
Y00847*
Y00847*
Y00848*
Y00848*
Y00849*
Y00849*
Y0085*
Y0085*
Y00851*
Y00852*
Y00852*
Y00853*
Y00853*
Y00854*
Y00854*
Y00855*
Y00855*
Y00856*
Y00856*
Y00857*
Y00857*
Y00858*
Y00859*
Y00859*
Y0086*
Y0086*
Y00861*
Y00861*
Y00862*
Y00862*
Y00863*
Y00863*
Y00864*
Y00865*
Y00865*
Y00866*
Y00866*
Y00867*
Y00867*
Y00868*
Y00868*
Y00869*
Y00869*
Y0087*
Y0087*
Y00871*
Y00872*
Y00872*
Y00873*
Y00873*
Y00874*
Y00874*
Y00875*
Y00875*
Y00876*
Y00876*
Y00877*
Y00877*
Y00878*
Y00879*
Y00879*
Y0088*
Y0088*
Y00881*
Y00881*
Y00882*
Y00882*
Y00883*
Y00883*
Y00884*
Y00885*
Y00885*
Y00886*
Y00886*
Y00887*
Y00887*
Y00888*
Y00888*
X06481Y00889*
X06482Y00889*
X06482Y0089*
X06482Y0089*
X06482Y00891*
X06483Y00891*
X06483Y00891*
X06483Y00891*
X06483Y00892*
X06484Y00892*
X06484Y00892*
X06484Y00893*
X06485Y00893*
X06485Y00893*
X06486Y00893*
X06487*
X06487Y00893*
X06488Y00893*
X06488Y00893*
X06489Y00892*
X06489Y00892*
X0652*
Y00892*
X0652Y00893*
X06521Y00893*
X06521Y00893*
X06522Y00893*
X06522*
X06523Y00893*
X06523*
X06523*
X06523Y00893*
X06524*
X06524Y00893*
G37*
G36*
X0641Y00894D02*
X06411Y00894D01*
X06411Y00894*
X06412Y00893*
X06412Y00893*
X06413Y00893*
X06413Y00892*
X06413Y00892*
X06413Y00891*
X06414Y00891*
X06414Y0089*
X06414Y0089*
Y00889*
Y00889*
Y00888*
Y00888*
Y00887*
Y00887*
Y00886*
Y00886*
Y00885*
Y00885*
Y00884*
Y00883*
Y00883*
Y00882*
Y00882*
Y00881*
Y00881*
Y0088*
Y0088*
Y00879*
Y00879*
Y00878*
Y00877*
Y00877*
Y00876*
Y00876*
Y00875*
Y00875*
Y00874*
Y00874*
Y00873*
Y00873*
Y00872*
Y00872*
Y00871*
Y0087*
Y0087*
Y00869*
Y00869*
Y00868*
Y00868*
Y00867*
Y00867*
Y00866*
Y00866*
Y00865*
Y00865*
Y00864*
Y00863*
Y00863*
Y00862*
Y00862*
Y00861*
X06414Y00861*
X06414Y0086*
X06413Y0086*
X06413Y00859*
X06413Y00859*
X06413Y00858*
X06412Y00858*
X06412Y00858*
X06411Y00858*
X06411Y00857*
X0641Y00857*
X0641Y00857*
X06369*
X06369Y00857*
X06368Y00857*
X06368Y00858*
X06367Y00858*
X06367Y00858*
X06366Y00858*
X06366Y00859*
X06366Y00859*
X06365Y0086*
X06365Y0086*
X06365Y00861*
X06365Y00861*
Y00862*
Y00862*
Y00863*
Y00863*
Y00864*
Y00865*
Y00865*
Y00866*
Y00866*
Y00867*
Y00867*
Y00868*
Y00868*
Y00869*
Y00869*
Y0087*
Y0087*
Y00871*
Y00872*
Y00872*
Y00873*
Y00873*
Y00874*
Y00874*
Y00875*
Y00875*
Y00876*
Y00876*
Y00877*
Y00877*
Y00878*
Y00879*
Y00879*
Y0088*
Y0088*
Y00881*
Y00881*
Y00882*
Y00882*
Y00883*
Y00883*
Y00884*
Y00885*
Y00885*
Y00886*
Y00886*
Y00887*
Y00887*
Y00888*
Y00888*
Y00889*
Y00889*
Y0089*
X06365Y0089*
X06365Y00891*
X06365Y00891*
X06366Y00892*
X06366Y00892*
X06366Y00893*
X06367Y00893*
X06367Y00893*
X06368Y00894*
X06368Y00894*
X06369Y00894*
X06369Y00894*
X0641*
X0641Y00894*
G37*
G54D38*
X04375Y0386D03*
X0445D03*
Y03776D03*
X04413D03*
G54D39*
X04375Y03776D03*
G54D71*
X04909Y02808D03*
Y03961D03*
G54D84*
X0147Y00245D03*
G54D85*
X02446Y00111D03*
G54D86*
X02545Y00137D03*
X02466D03*
X02348D03*
X0282D03*
X01915D03*
X02033D03*
X02663D03*
X02702D03*
X0286D03*
X02978D03*
X0219D03*
X01994D03*
X01954D03*
X03017D03*
X02309D03*
X02112D03*
X02151D03*
X02387D03*
X02427D03*
X02584D03*
X02624D03*
X02742D03*
X02781D03*
X02899D03*
X02938D03*
X02505D03*
X02072D03*
X01797D03*
X01836D03*
X01875D03*
X03096D03*
G54D87*
X03057Y00157D03*
G54D88*
X0415Y03603D03*
X04204D03*
X04638Y04204D03*
X04692D03*
X03532Y02797D03*
X03477D03*
X0609Y03556D03*
X06035D03*
X06842Y01816D03*
X06897D03*
X06736Y01818D03*
X0679D03*
X06311Y0246D03*
X06365D03*
X04112Y03701D03*
X04167D03*
X05161Y04208D03*
X05216D03*
X04638Y04149D03*
X04692D03*
G54D89*
X00966Y0072D03*
X00907D03*
X05159Y04153D03*
X05218D03*
X00966Y01216D03*
X00907D03*
X00959Y01747D03*
X009D03*
X0097Y02275D03*
X00911D03*
G54D90*
X00653Y01894D03*
Y0201D03*
Y02422D03*
Y02538D03*
Y00847D03*
Y00963D03*
Y01375D03*
Y01491D03*
G54D91*
X00713Y01952D03*
Y0248D03*
Y00905D03*
Y01433D03*
G54D92*
X01248Y04052D03*
Y04105D03*
X01047Y04052D03*
Y04105D03*
X00846Y04052D03*
Y04105D03*
X00641Y04052D03*
Y04105D03*
G54D93*
X02209Y03716D03*
Y03645D03*
X04339Y02851D03*
Y0278D03*
X06334Y02181D03*
Y0211D03*
X06659Y02095D03*
Y02166D03*
X06275Y02822D03*
Y02893D03*
X06362Y02822D03*
Y02893D03*
X04104Y03841D03*
Y0377D03*
X02639Y03606D03*
Y03535D03*
X03693Y03117D03*
Y03188D03*
X04064Y02851D03*
Y0278D03*
X03959Y02851D03*
Y0278D03*
X04234Y02851D03*
Y0278D03*
G54D94*
X06679Y0242D03*
Y02802D03*
X06319Y0146D03*
Y01842D03*
G54D95*
X06687Y01611D03*
X06632D03*
X06687Y01671D03*
X06632D03*
X06687Y01721D03*
X06632D03*
X06687Y01776D03*
X06632D03*
X06152Y02171D03*
X06097D03*
X06847Y02096D03*
X06902D03*
X0372Y00645D03*
X03665D03*
X06314Y02673D03*
X0637D03*
X06314Y02606D03*
X0637D03*
X06314Y02535D03*
X0637D03*
X06314Y0274D03*
X0637D03*
X05622Y03358D03*
X05677D03*
G54D96*
X04394Y03929D03*
X04439D03*
G54D97*
X03125Y02787D03*
Y02732D03*
X03358Y02791D03*
Y02736D03*
X04523Y03846D03*
Y03791D03*
X04454Y03033D03*
Y03088D03*
X04394Y03033D03*
Y03088D03*
X04334Y03033D03*
Y03088D03*
X04274Y03033D03*
Y03088D03*
X04219Y03033D03*
Y03088D03*
X04164Y03033D03*
Y03088D03*
X04109Y03033D03*
Y03088D03*
X03771Y03137D03*
Y03082D03*
X0272Y03598D03*
Y03543D03*
X02139Y03653D03*
Y03708D03*
X06586Y03059D03*
Y03003D03*
G54D98*
X0371Y03786D03*
X03659D03*
X0371Y03861D03*
X03659D03*
G54D99*
X06064Y02387D03*
Y02334D03*
X06939Y01879D03*
Y01932D03*
G54D100*
X02212Y01037D03*
X0298Y02357D03*
X02586Y02517D03*
X02488D03*
X02389D03*
X02291D03*
X02881Y02357D03*
X02783D03*
X02685D03*
X02586D03*
X02488D03*
X02389D03*
X02291D03*
X0294D03*
X0296D03*
X02901D03*
X02921D03*
X02842D03*
X02862D03*
X02803D03*
X02822D03*
X02744D03*
X02763D03*
X02704D03*
X02724D03*
X02645D03*
X02665D03*
X02606D03*
X02625D03*
X02547D03*
X02566D03*
X02507D03*
X02527D03*
X02448D03*
X02468D03*
X02409D03*
X02429D03*
X0235D03*
X0237D03*
X02212Y02517D03*
X02232D03*
Y02357D03*
X02212D03*
X02251Y02517D03*
X02271D03*
X02409D03*
X02429D03*
X0235D03*
X0237D03*
X02507D03*
X02527D03*
X02448D03*
X02468D03*
X02606D03*
X02547D03*
X02625D03*
X02566D03*
X02251Y02357D03*
X02311D03*
X0233D03*
X02271D03*
X02311Y02517D03*
X0233D03*
X02803Y01037D03*
X02822D03*
X02862Y00877D03*
X02881D03*
X02744D03*
X02763D03*
X02685Y01037D03*
X02704D03*
X02586Y00877D03*
Y01037D03*
X02645Y00877D03*
X02625D03*
X02744Y01037D03*
X02763D03*
X02803Y00877D03*
X02822D03*
X02685D03*
X02704D03*
X02625Y01037D03*
X02645D03*
X02232Y00877D03*
X02429D03*
X0237D03*
X0235D03*
X0233D03*
X02291D03*
X02389D03*
X02488D03*
X02527D03*
X02547D03*
X02566D03*
X02448D03*
X02468D03*
X02251D03*
X02271D03*
X02566Y01037D03*
X0237D03*
X02389D03*
X02429D03*
X02468D03*
X02488D03*
X02448D03*
X02291D03*
X02271D03*
X02251D03*
X02232D03*
X0235D03*
X0233D03*
X02547D03*
X02527D03*
X02862D03*
X02881D03*
X02921Y00877D03*
Y01037D03*
X0294Y00877D03*
Y01037D03*
X0298Y00877D03*
Y01037D03*
X0296D03*
Y00877D03*
X02901Y01037D03*
X02842D03*
X02783D03*
X02724D03*
X02665D03*
X02606D03*
X02507D03*
X02409D03*
X02311D03*
X02901Y00877D03*
X02842D03*
X02783D03*
X02724D03*
X02665D03*
X02606D03*
X02507D03*
X02409D03*
X02311D03*
X02212D03*
X02645Y02517D03*
X02665D03*
X02685D03*
X02704D03*
X02724D03*
X02744D03*
X02763D03*
X02783D03*
X02803D03*
X02822D03*
X02842D03*
X02862D03*
X02881D03*
X02901D03*
X02921D03*
X0294D03*
X0296D03*
X0298D03*
G54D101*
X01696Y01262D03*
X0357D03*
X01696Y02142D03*
X0357D03*
G54D102*
X02156Y02437D03*
Y00957D03*
X03036D03*
Y02437D03*
G54D103*
X03491Y01397D03*
Y01377D03*
Y01456D03*
Y01476D03*
Y01771D03*
Y01495D03*
Y01791D03*
Y01889D03*
Y0185D03*
Y01869D03*
Y0183D03*
X03651Y01869D03*
Y01889D03*
Y01928D03*
X03491Y01338D03*
Y01358D03*
X03651Y01791D03*
Y01771D03*
Y0185D03*
Y0183D03*
Y01948D03*
Y01988D03*
Y01968D03*
X03491Y01988D03*
Y01968D03*
X03651Y01692D03*
X03491Y01633D03*
Y01673D03*
Y01653D03*
Y01692D03*
X03651Y01732D03*
Y01751D03*
Y01653D03*
Y01574D03*
Y01554D03*
Y01673D03*
Y01633D03*
X03491Y01928D03*
Y01554D03*
Y02007D03*
Y01909D03*
Y0181D03*
Y01712D03*
Y01613D03*
Y01515D03*
Y01417D03*
X03651Y02007D03*
Y01909D03*
Y0181D03*
Y01712D03*
Y01613D03*
Y01515D03*
Y01417D03*
X03491Y01948D03*
X03651Y01594D03*
X03491Y01535D03*
X03651Y01495D03*
Y01476D03*
Y01456D03*
Y01436D03*
Y01397D03*
Y01377D03*
Y01358D03*
Y01338D03*
X03491Y01318D03*
X03651D03*
X03491Y01732D03*
Y01751D03*
X03651Y01535D03*
X03491Y01574D03*
Y01594D03*
Y01436D03*
Y02086D03*
Y02066D03*
Y02047D03*
Y02027D03*
X03651Y02086D03*
Y02066D03*
Y02047D03*
Y02027D03*
X01776Y01633D03*
Y01614D03*
Y01869D03*
Y02027D03*
Y01909D03*
Y0183D03*
Y01948D03*
Y01732D03*
Y01771D03*
X01616Y01928D03*
Y0185D03*
Y01909D03*
Y02027D03*
X01776Y02007D03*
Y01968D03*
Y01456D03*
Y01673D03*
X01616Y01869D03*
Y01968D03*
X01776Y01928D03*
Y0185D03*
Y0181D03*
Y01653D03*
X01616Y02007D03*
X01776Y01751D03*
Y01712D03*
X01616Y01948D03*
X01776Y01554D03*
Y01574D03*
X01616Y01515D03*
Y01456D03*
Y0181D03*
Y0183D03*
X01776Y01436D03*
X01616Y01358D03*
X01776Y01338D03*
X01616Y01574D03*
Y01436D03*
Y01535D03*
Y01554D03*
Y01614D03*
Y01732D03*
Y01673D03*
Y01377D03*
Y01476D03*
Y01417D03*
Y01751D03*
X01776Y01358D03*
X01616Y01338D03*
Y01633D03*
Y01771D03*
X01776Y01377D03*
Y01318D03*
Y01417D03*
X01616Y01318D03*
X01776Y01476D03*
X01616Y01712D03*
Y01653D03*
X01776Y01515D03*
X01616Y02047D03*
X01776D03*
Y01397D03*
Y01495D03*
Y01594D03*
Y01692D03*
Y01791D03*
Y01889D03*
Y01988D03*
X01616Y01397D03*
Y01495D03*
Y01594D03*
Y01692D03*
Y01791D03*
Y01889D03*
Y01988D03*
Y02086D03*
X01776D03*
Y02066D03*
Y01535D03*
X01616Y02066D03*
G54D104*
X03111Y02937D03*
Y02987D03*
Y03037D03*
Y03087D03*
Y03137D03*
Y03187D03*
Y03237D03*
Y03287D03*
X02756Y02937D03*
Y02987D03*
Y03037D03*
Y03087D03*
Y03137D03*
Y03187D03*
Y03237D03*
Y03287D03*
G54D105*
X02199Y04275D03*
X02465D03*
G54D106*
X02281Y0417D03*
X02306D03*
X02332D03*
X02358D03*
X02383D03*
G54D107*
X0243Y04173D03*
X02234D03*
G54D108*
X02377Y04275D03*
G54D109*
X02271Y04275D03*
G54D110*
X03808Y04023D03*
X03839D03*
X03871D03*
X03902D03*
X03934D03*
G54D111*
X03696Y04244D03*
Y04027D03*
X04046D03*
Y04244D03*
G54D112*
X03495Y0375D03*
X03444D03*
X03469Y03661D03*
X0286Y0375D03*
X02809D03*
X02834Y03661D03*
X02745Y0375D03*
X02694D03*
X02719Y03661D03*
X0327Y0375D03*
X03219D03*
X03244Y03661D03*
G54D113*
X01631Y04199D03*
Y04174D03*
Y04149D03*
Y04124D03*
Y04099D03*
Y04074D03*
Y04049D03*
Y04024D03*
X01846Y04199D03*
Y04174D03*
Y04149D03*
Y04124D03*
Y04099D03*
Y04074D03*
Y04049D03*
Y04024D03*
X03772Y03858D03*
Y03833D03*
Y03808D03*
Y03783D03*
Y03758D03*
Y03733D03*
Y03708D03*
Y03683D03*
X03987Y03858D03*
Y03833D03*
Y03808D03*
Y03783D03*
Y03758D03*
Y03733D03*
Y03708D03*
Y03683D03*
G54D114*
X06157Y02241D03*
Y02291D03*
Y02341D03*
Y02391D03*
X06352D03*
Y02341D03*
Y02291D03*
Y02241D03*
X06832Y02031D03*
Y01981D03*
Y01931D03*
Y01881D03*
X06637D03*
Y01931D03*
Y01981D03*
Y02031D03*
G54D115*
X06197Y03701D03*
X06341D03*
X05887D03*
X06031D03*
X06346Y03566D03*
X06202D03*
G54D116*
X06726Y03294D03*
X06943D03*
Y03168D03*
X06726D03*
G54D117*
X03569Y03385D03*
G54D118*
X03392Y03395D03*
X0351Y03206D03*
X03333D03*
Y03395D03*
X03569Y03206D03*
X0351Y03395D03*
X03451D03*
X03392Y03206D03*
X03451D03*
G54D119*
X03525Y02995D03*
Y02948D03*
X03444D03*
Y02995D03*
G54D120*
X03484Y03051D03*
Y02892D03*
G54D121*
X03531Y02892D03*
Y03051D03*
X03438Y02892D03*
Y03051D03*
G54D122*
X02944Y03951D03*
Y04221D03*
X03044Y03951D03*
Y04221D03*
X03144Y03951D03*
Y04221D03*
X03244Y03951D03*
Y04221D03*
X03344Y03951D03*
Y04221D03*
G54D123*
X03349Y03745D03*
Y03666D03*
X02944Y03745D03*
Y03666D03*
X03044Y03745D03*
Y03666D03*
X03144Y03745D03*
Y03666D03*
G54D124*
X05091Y04206D03*
X04957D03*
X04566D03*
X04432D03*
G54D125*
X04068Y01779D03*
X03911D03*
X04068Y01759D03*
X03911D03*
X04068Y01739D03*
X03911D03*
X04068Y01719D03*
X03911D03*
X04068Y01699D03*
X03911D03*
X04068Y01679D03*
X03911D03*
X04068Y01659D03*
X03911D03*
X04068Y01639D03*
X03911D03*
X04068Y01619D03*
X03911D03*
Y01599D03*
X04068D03*
G54D126*
X06479Y0315D03*
X06459D03*
X0644D03*
X0642D03*
Y03332D03*
X0644D03*
X06459D03*
X06479D03*
G54D127*
X06511Y03152D03*
X06388D03*
Y03172D03*
Y03191D03*
Y03211D03*
Y03231D03*
Y0325D03*
Y0327D03*
Y0329D03*
Y03309D03*
Y03329D03*
X06511D03*
Y03309D03*
Y0329D03*
Y0327D03*
Y0325D03*
Y03231D03*
Y03211D03*
Y03172D03*
Y03191D03*
G54D128*
X04149Y02842D03*
Y02789D03*
X04434Y02842D03*
Y02789D03*
G54D129*
X00932Y00906D03*
X01157D03*
Y01956D03*
X00932D03*
X01157Y02481D03*
X00932D03*
Y01431D03*
X01157D03*
G54D130*
X01249Y04197D03*
Y04254D03*
X03589Y03909D03*
Y03852D03*
Y03727D03*
Y03784D03*
X00644Y04254D03*
Y04197D03*
X00846Y04254D03*
Y04197D03*
X01048D03*
Y04254D03*
G54D131*
X04039Y03092D03*
Y03029D03*
X06469Y02302D03*
Y02239D03*
X06519Y02017D03*
Y01954D03*
X04194Y03837D03*
Y03774D03*
X03688Y03329D03*
Y03266D03*
X06604Y03327D03*
Y03264D03*
Y03129D03*
Y03192D03*
G54D132*
X03249Y02845D03*
X03229D03*
Y02784D03*
X03249D03*
G54D133*
X03209Y02834D03*
Y02814D03*
Y02795D03*
X03269D03*
Y02814D03*
Y02834D03*
G54D134*
X05812Y03361D03*
X05741D03*
X067Y01421D03*
X06629D03*
X067Y01531D03*
X06629D03*
X0651Y03071D03*
X06439D03*
X03659Y00726D03*
X0373D03*
X01873Y04276D03*
X01802D03*
X04209Y03246D03*
X0428D03*
G54D135*
X04332Y03603D03*
X04275D03*
G54D136*
X06749Y02088D03*
Y02143D03*
X06234Y02128D03*
Y02183D03*
X07Y01878D03*
Y01932D03*
X06003Y02335D03*
Y02389D03*
X02146Y02679D03*
Y02624D03*
X06122Y02433D03*
Y02488D03*
X01933Y04129D03*
Y04074D03*
G54D137*
X02503Y00573D03*
Y00607D03*
X03055Y00573D03*
Y00607D03*
G54D138*
X02509Y0364D03*
Y03483D03*
Y03562D03*
Y03404D03*
X02334Y0364D03*
Y03562D03*
Y03483D03*
Y03404D03*
G54D139*
X01727Y04273D03*
X01664D03*
G54D140*
X01346Y04141D03*
Y04082D03*
Y03978D03*
Y04037D03*
X02151Y04074D03*
Y04015D03*
X02212Y04074D03*
Y04015D03*
X02387Y02958D03*
Y02899D03*
G54D141*
X02422Y03082D03*
Y03239D03*
Y03443D03*
Y03601D03*
G54D142*
X00199Y02481D03*
Y01956D03*
Y01431D03*
Y00906D03*
G54D143*
X00299Y02581D03*
Y02381D03*
X00099D03*
Y02581D03*
X00299Y02056D03*
Y01856D03*
X00099D03*
Y02056D03*
X00299Y01531D03*
Y01331D03*
X00099D03*
Y01531D03*
X00299Y01006D03*
Y00806D03*
X00099D03*
Y01006D03*
G54D144*
X0299Y02437D03*
X03571Y02096D03*
Y01308D03*
X02202Y02437D03*
X01696Y01308D03*
Y02096D03*
X02202Y00957D03*
X0299D03*
G54D145*
X03617Y02485D03*
X01652Y00915D03*
X01651Y02485D03*
X03617Y00915D03*
G54D146*
X03784Y04126D03*
X03958D03*
G54D147*
X02994Y04086D03*
X03294D03*
G54D148*
X05327Y01007D03*
X04327Y02307D03*
X05127Y01007D03*
X04927D03*
X04727Y02307D03*
X04927D03*
X05127D03*
X05327D03*
G54D149*
X04327Y01007D03*
G54D150*
X04298Y02595D03*
X0418D03*
X04062D03*
X03979Y0089D03*
Y02489D03*
X05578D03*
Y01689D03*
Y0089D03*
G54D151*
X05723Y03844D03*
Y04025D03*
X06569Y03806D03*
Y03589D03*
X06734Y03806D03*
Y03589D03*
X069D03*
Y03806D03*
G54D152*
X06119Y03819D03*
G54D153*
X06119Y04056D03*
G54D154*
X05934Y03937D03*
G54D155*
X02043Y04057D03*
Y04157D03*
X01457Y04053D03*
Y04153D03*
G54D156*
X02043Y04257D03*
X01457Y04253D03*
G54D157*
X06569Y04093D03*
X069D03*
G54D158*
X00285Y04152D03*
Y00368D03*
G54D159*
X02645Y0227D03*
X02618Y02299D03*
X02671Y02291D03*
X06978Y0183D03*
X02314Y00933D03*
X02413D03*
X02515D03*
X02905Y00937D03*
X02901Y01106D03*
X0285D03*
X02787D03*
X02728D03*
X02665D03*
X0261D03*
X02511Y01105D03*
X02409Y01106D03*
X02311D03*
X02322Y02429D03*
X02421D03*
X02484D03*
X02783Y02433D03*
X02874Y0229D03*
X02779Y02601D03*
X02688D03*
X0259D03*
X02488Y02574D03*
X02385Y02613D03*
X02279Y02614D03*
X03051Y02732D03*
X03414Y02892D03*
Y02736D03*
X04385Y03661D03*
X04393Y03976D03*
X04318Y03507D03*
X04116Y03597D03*
X03657Y03296D03*
X03747Y01679D03*
X03718Y01713D03*
X03712Y01673D03*
X0359Y01662D03*
X04523Y03736D03*
X0307Y03393D03*
X04438Y03354D03*
X03542Y03318D03*
X03437Y03476D03*
X03622Y03486D03*
X04437Y03661D03*
X04053Y03641D03*
X0333Y03301D03*
X03344Y02996D03*
X03342Y02263D03*
X03368Y0305D03*
X01015Y01705D03*
X01721Y01685D03*
X01003Y01177D03*
X01893Y01685D03*
X0167D03*
X03877Y03078D03*
X03799Y03201D03*
X02633Y02921D03*
X02414Y03199D03*
X02413Y03295D03*
X02591Y03186D03*
X02462Y03172D03*
X0259Y03288D03*
X02418Y03118D03*
X0522Y04086D03*
X02258Y03741D03*
X0272Y03494D03*
X06335Y03147D03*
X06262Y0322D03*
X06287Y03195D03*
X06274Y02949D03*
X06362Y02952D03*
X0645Y02462D03*
Y02535D03*
X06452Y02606D03*
X06451Y02673D03*
X0645Y0274D03*
X06587Y01529D03*
X06594Y01673D03*
Y0161D03*
Y01775D03*
Y0172D03*
X03602Y00641D03*
X02948Y02456D03*
X02252Y02613D03*
X01674Y01989D03*
X03379Y01386D03*
X03732Y01418D03*
X02579Y02281D03*
X02708Y00976D03*
X02803Y02307D03*
X02575Y02412D03*
X03719Y01996D03*
X02685Y02311D03*
X03803Y01691D03*
X02958Y02621D03*
X0245Y02282D03*
X01714Y01595D03*
X03773Y01666D03*
X02606Y00931D03*
X02881Y02566D03*
X03554Y01941D03*
X0292Y02428D03*
X03864Y01511D03*
X03404Y01363D03*
X02841Y02263D03*
X02767Y00976D03*
X0341Y01713D03*
X03414Y01805D03*
X02799Y00976D03*
X03298Y01971D03*
X02894Y02431D03*
X02759Y00795D03*
X03571Y02058D03*
X02726Y02293D03*
X0274Y00976D03*
X02826Y00795D03*
X02821Y02601D03*
X02985Y02287D03*
X02494Y02696D03*
X01822Y01674D03*
X02625Y00795D03*
X03804Y0184D03*
X02702Y02289D03*
X02893Y00795D03*
X02732D03*
X02599Y02436D03*
X01718Y01792D03*
X02475Y02291D03*
X01879Y01811D03*
X03719Y01921D03*
X03554Y01891D03*
X01568Y02067D03*
X01675Y01891D03*
X01567Y01285D03*
X02826Y00976D03*
X02394Y0272D03*
X02942Y02286D03*
X03554Y01991D03*
X03571Y02033D03*
X02692Y00795D03*
X02598D03*
X01719Y01536D03*
X02272Y02463D03*
X02681Y00976D03*
X03594Y01514D03*
X02409Y02314D03*
X03406Y01461D03*
X03392Y01871D03*
X02494Y02661D03*
X03407Y01411D03*
X02499Y02236D03*
X02409Y02283D03*
X02649Y00976D03*
X01718Y01497D03*
X01619Y02121D03*
X02622Y00976D03*
X01798Y01304D03*
X01671Y01792D03*
X02665Y00795D03*
X01671Y01399D03*
X01754Y02126D03*
X02799Y00795D03*
X03924Y01536D03*
X03549Y01441D03*
X01897Y01516D03*
X02624Y02461D03*
X03329Y01826D03*
X03719Y01766D03*
X01884Y02071D03*
X03834Y01481D03*
X0167Y01595D03*
X02862Y00795D03*
X03894Y01566D03*
X01716Y01399D03*
X03224Y01661D03*
X03379Y01336D03*
X01671Y01497D03*
X0233Y02215D03*
X03413Y01573D03*
X03197Y01714D03*
X01721Y01989D03*
Y0189D03*
X03549Y01413D03*
X03439Y0187D03*
X03252Y01661D03*
X03554Y01841D03*
X04039Y03784D03*
X02692Y02721D03*
X02511Y00405D03*
X0261Y00279D03*
X02578D03*
X0298Y00409D03*
X02821Y00407D03*
X02748Y00282D03*
X02469Y0041D03*
X02905Y00279D03*
X02878Y00249D03*
X02854Y00405D03*
X02779Y00279D03*
X02665Y00405D03*
X02704D03*
X0235D03*
X02389D03*
X02937Y00279D03*
X02957Y00251D03*
X03019Y00405D03*
X02447Y00242D03*
X02413Y00279D03*
X02444D03*
X02636Y00247D03*
X02799Y00251D03*
X02546Y00244D03*
X03097Y00251D03*
X01797Y00355D03*
X02034Y00246D03*
X01916Y00244D03*
X02309Y00246D03*
X01393Y01816D03*
X0099Y00687D03*
X04794Y02808D03*
X03183Y03135D03*
X03277Y02963D03*
X03197Y0297D03*
X03491Y03103D03*
X03188Y03187D03*
X0323Y03235D03*
X03358Y03448D03*
X02419Y02788D03*
X02146Y02753D03*
X03275Y03141D03*
X03056Y01811D03*
X02254Y03536D03*
X02579Y03486D03*
X02389Y03481D03*
X02321Y03361D03*
X02434Y03546D03*
X02634Y03406D03*
X00996Y02256D03*
X02004Y01336D03*
X02028Y01361D03*
X02549Y01755D03*
X02473Y0298D03*
X02146Y04103D03*
X02253Y04086D03*
X01408Y0398D03*
X01345Y04175D03*
X00937Y02317D03*
X02353Y04017D03*
X01726Y04329D03*
X01788D03*
X04477Y03135D03*
X04064Y02722D03*
X06628Y01372D03*
X04039Y02406D03*
X04134Y01651D03*
X03994Y01551D03*
X04134Y01751D03*
X04151Y01623D03*
X03968Y01671D03*
X03969Y01552D03*
X03944Y01816D03*
X04131Y01686D03*
X04179Y01601D03*
X04034Y01546D03*
X03996Y01711D03*
X04064Y01796D03*
Y01511D03*
X03263Y03303D03*
X0396Y02724D03*
X01569Y04171D03*
X02076Y00255D03*
Y00287D03*
X02112D03*
X02151D03*
X02112Y00255D03*
X02151D03*
X01832D03*
X01852D03*
X01872D03*
X01832Y00287D03*
X01852D03*
X01872D03*
X06647Y03129D03*
X04339Y02725D03*
X04503Y02789D03*
X03829Y03806D03*
X05577Y02214D03*
X02694Y01481D03*
X02384Y01941D03*
X0383Y03762D03*
X06334Y03266D03*
X03744Y03261D03*
X03395Y04222D03*
X04272Y03135D03*
X05634Y02236D03*
X02626Y0177D03*
X06304Y03121D03*
X03939D03*
X04208Y03135D03*
X02604Y01734D03*
X06649Y03003D03*
X04152Y03135D03*
X02299Y01916D03*
X01248Y02D03*
X02579Y0179D03*
X04068Y03135D03*
X02674Y03501D03*
X04234Y02725D03*
X06456Y03009D03*
X01691Y04079D03*
X02259Y03261D03*
X03374Y03273D03*
X06476Y03231D03*
X04333Y03135D03*
X01557Y04229D03*
X03806Y03235D03*
X01261Y02482D03*
X04114Y03135D03*
X06648Y03341D03*
X02888Y04221D03*
X01749Y0411D03*
X0257Y04283D03*
X01459Y03147D03*
X0144Y03557D03*
X01903Y04018D03*
X0229Y04217D03*
X03623Y02587D03*
X03491Y03297D03*
X03744Y03342D03*
X03394Y03447D03*
X03717Y03072D03*
X02799Y03616D03*
X03589Y01711D03*
X05733Y03556D03*
X05676Y03546D03*
X03603Y00682D03*
X02478Y00937D03*
X06694Y0183D03*
X06699Y01881D03*
X06949Y02095D03*
X06607Y02176D03*
X06395Y02111D03*
X06048Y02171D03*
X06003Y0243D03*
X06274Y02391D03*
X0491Y04203D03*
X04387Y04206D03*
X03777Y04023D03*
X04085Y03892D03*
X04194Y03884D03*
X04431Y03135D03*
X0286Y03787D03*
X02724Y03729D03*
X03531Y0366D03*
X03269Y03788D03*
X01242Y01472D03*
X01256Y00942D03*
X00654Y0079D03*
X00655Y01028D03*
X00654Y01314D03*
X00653Y01551D03*
X00654Y01839D03*
Y02073D03*
Y02365D03*
X00653Y02593D03*
X02206Y01298D03*
X02205Y032D03*
X02502Y01316D03*
X02525Y02463D03*
X03498Y02341D03*
X02429Y02621D03*
X01004Y00906D03*
X02446Y01437D03*
X01008Y0143D03*
X02409Y01967D03*
X01009Y01956D03*
X0102Y02481D03*
X02643Y01616D03*
X02666Y0164D03*
X01884Y03601D03*
X01754Y03661D03*
X03424Y03636D03*
X01549Y03621D03*
X03239Y03596D03*
X01574D03*
X03539Y03806D03*
X03219D03*
X02722Y03786D03*
X02139Y03611D03*
X02084Y03896D03*
X02083Y01411D03*
X02059Y01386D03*
Y03871D03*
X02029Y03836D03*
X01294Y04256D03*
X02004Y03816D03*
X05274Y03511D03*
X02679Y03661D03*
X02774Y03566D03*
X02993Y03751D03*
X03699D03*
X03014Y03831D03*
X03699Y03836D03*
X04254Y03776D03*
X02894Y01561D03*
X02919Y01536D03*
X02274Y01506D03*
X02719Y01591D03*
X06424Y02181D03*
X04754Y04115D03*
X01779Y04156D03*
X03504Y04086D03*
X03854Y03151D03*
X03829Y03176D03*
X06439Y03191D03*
X06354Y03331D03*
X06444Y03291D03*
X03302Y03344D03*
X06409Y03371D03*
X06447Y03396D03*
X06479Y03426D03*
X06509Y03456D03*
X03469D03*
X01849Y03701D03*
X06294D03*
G54D160*
X05964Y03555D03*
X06196Y02484D03*
X06838Y01649D03*
G54D161*
X02531Y03853D03*
Y0283D03*
X00149D03*
Y03853D03*
M02*